FILE_TYPE = MACRO_DRAWING;
SET COLOR_WIRE YELLOW;
SET COLOR_PROP MONO;
SET COLOR_DOT WHITE;
SET COLOR_ARC YELLOW;
SET COLOR_BODY GREEN;
SET COLOR_NOTE MONO;
SET PROP_DISPLAY VALUE;
SET PAGE_NUMBER P212;
FORCEADD IR354XX..1
(1250 3950);
FORCEPROP 2 LASTPIN (1750 4500) $PN 38
J 0
(1760 4510);
DISPLAY 0.617021 (1760 4510);
PAINT MONO (1760 4510);
FORCEPROP 2 LASTPIN (750 3850) $PN 34
J 2
(740 3860);
DISPLAY 0.617021 (740 3860);
PAINT MONO (740 3860);
FORCEPROP 1 LAST PART_NUMBER H73684-001
J 0
(800 3250);
DISPLAY 0.617021 (800 3250);
PAINT BLUE (800 3250);
FORCEPROP 2 LASTPIN (750 3650) $PN 33
J 2
(740 3660);
DISPLAY 0.617021 (740 3660);
PAINT MONO (740 3660);
FORCEPROP 2 LASTPIN (750 3750) $PN 39
J 2
(740 3760);
DISPLAY 0.617021 (740 3760);
PAINT MONO (740 3760);
FORCEPROP 2 LASTPIN (1750 3550) $PN 2
J 0
(1760 3560);
DISPLAY 0.617021 (1760 3560);
PAINT MONO (1760 3560);
FORCEPROP 2 LASTPIN (1750 3450) $PN 7
J 0
(1760 3460);
DISPLAY 0.617021 (1760 3460);
PAINT MONO (1760 3460);
FORCEPROP 2 LASTPIN (750 4200) $PN 35
J 2
(740 4210);
DISPLAY 0.617021 (740 4210);
PAINT MONO (740 4210);
FORCEPROP 2 LASTPIN (750 4100) $PN 1
J 2
(740 4110);
DISPLAY 0.617021 (740 4110);
PAINT MONO (740 4110);
FORCEPROP 2 LASTPIN (1750 3400) $PN 5
J 0
(1760 3410);
DISPLAY 0.617021 (1760 3410);
PAINT MONO (1760 3410);
FORCEPROP 2 LASTPIN (1750 3650) $PN 10
J 0
(1760 3660);
DISPLAY 0.617021 (1760 3660);
PAINT MONO (1760 3660);
FORCEPROP 2 LASTPIN (1750 4000) $PN 36
J 0
(1760 4010);
DISPLAY 0.617021 (1760 4010);
PAINT MONO (1760 4010);
FORCEPROP 2 LASTPIN (750 4400) $PN 25
J 2
(740 4410);
DISPLAY 0.617021 (740 4410);
PAINT MONO (740 4410);
FORCEPROP 2 LASTPIN (750 4450) $PN 30
J 2
(740 4460);
DISPLAY 0.617021 (740 4460);
PAINT MONO (740 4460);
FORCEPROP 2 LASTPIN (750 4500) $PN 3
J 2
(740 4510);
DISPLAY 0.617021 (740 4510);
PAINT MONO (740 4510);
FORCEPROP 1 LAST MATERIAL IC
J 0
(800 4700);
DISPLAY 0.617021 (800 4700);
PAINT SKYBLUE (800 4700);
FORCEPROP 2 LASTPIN (750 4000) $PN 41
J 2
(740 4010);
DISPLAY 0.617021 (740 4010);
PAINT MONO (740 4010);
FORCEPROP 2 LASTPIN (1750 3500) $PN 40
J 0
(1760 3510);
DISPLAY 0.617021 (1760 3510);
PAINT MONO (1760 3510);
FORCEPROP 2 LASTPIN (750 3600) $PN 32
J 2
(740 3610);
DISPLAY 0.617021 (740 3610);
PAINT MONO (740 3610);
FORCEPROP 2 LASTPIN (1750 4300) $PN 37
J 0
(1760 4310);
DISPLAY 0.617021 (1760 4310);
PAINT MONO (1760 4310);
FORCEPROP 2 LASTPIN (750 3950) $PN 6
J 2
(740 3960);
DISPLAY 0.617021 (740 3960);
PAINT MONO (740 3960);
FORCEPROP 2 LASTPIN (750 4300) $PN 4
J 2
(740 4310);
DISPLAY 0.617021 (740 4310);
PAINT MONO (740 4310);
FORCEPROP 2 LASTPIN (1750 4250) $PN 31
J 0
(1760 4260);
DISPLAY 0.617021 (1760 4260);
PAINT MONO (1760 4260);
FORCEPROP 1 LAST LOCATION EU7C1
J 0
(800 4750);
DISPLAY 0.617021 (800 4750);
PAINT AQUA (800 4750);
FORCEPROP 2 LAST CDS_LIB mstr_discrete
J 0
(1250 3950);
PAINT ORANGE (1250 3950);
DISPLAY INVISIBLE (1250 3950);
FORCEPROP 2 LAST CDS_LOCATION EU7C1
J 0
(800 4750);
PAINT GREEN (800 4750);
DISPLAY INVISIBLE (800 4750);
FORCEPROP 2 LAST CDS_SEC 1
J 0
(800 4800);
PAINT MONO (800 4800);
DISPLAY INVISIBLE (800 4800);
FORCEPROP 2 LAST $SEC 1
J 0
(800 4800);
PAINT MONO (800 4800);
DISPLAY INVISIBLE (800 4800);
FORCEPROP 1 LAST PACK_TYPE SM
J 0
(800 4800);
PAINT SKYBLUE (800 4800);
DISPLAY INVISIBLE (800 4800);
FORCEPROP 1 LAST PATH I101
J 0
(1250 4700);
PAINT GREEN (1250 4700);
DISPLAY INVISIBLE (1250 4700);
FORCEPROP 1 LAST VALUE IR35412
J 1
(1250 4575);
DISPLAY 0.617021 (1250 4575);
PAINT SKYBLUE (1250 4575);
DISPLAY INVISIBLE (1250 4575);
FORCEADD GND..1
(3525 3950);
FORCEPROP 3 LASTPIN (3525 4000) SIG_NAME GND\g
J 0
(3535 4010);
DISPLAY 0.659574 (3535 4010);
PAINT MONO (3535 4010);
DISPLAY INVISIBLE (3535 4010);
FORCEPROP 1 LAST VOLTAGE 0
J 0
(3525 3950);
PAINT SKYBLUE (3525 3950);
DISPLAY INVISIBLE (3525 3950);
FORCEPROP 1 LAST PATH I102
J 0
(3600 3950);
DISPLAY 0.872340 (3600 3950);
PAINT AQUA (3600 3950);
DISPLAY INVISIBLE (3600 3950);
FORCEPROP 2 LAST CDS_LIB mstr_symbols
J 0
(3525 3950);
PAINT ORANGE (3525 3950);
DISPLAY INVISIBLE (3525 3950);
FORCEPROP 1 LAST SIZE 1B
J 0
(3600 3900);
DISPLAY 1.723404 (3600 3900);
PAINT GREEN (3600 3900);
DISPLAY INVISIBLE (3600 3900);
FORCEPROP 2 LAST BOM_COST PROC_VRD_VCCIN_CPU0
J 0
(3150 4025);
DISPLAY 1.446809 (3150 4025);
PAINT MONO (3150 4025);
DISPLAY INVISIBLE (3150 4025);
FORCEPROP 2 LAST ROOM PVSA_CPU1_PWR_VR
J 0
(2975 4025);
DISPLAY 1.936170 (2975 4025);
PAINT ORANGE (2975 4025);
DISPLAY INVISIBLE (2975 4025);
FORCEPROP 1 LAST BODY_TYPE PLUMBING
J 0
(3480 3907);
DISPLAY 0.340426 (3480 3907);
PAINT GREEN (3480 3907);
DISPLAY INVISIBLE (3480 3907);
FORCEPROP 1 LAST HDL_POWER GND
J 0
(3525 4100);
DISPLAY 1.723404 (3525 4100);
PAINT GREEN (3525 4100);
DISPLAY INVISIBLE (3525 4100);
FORCEADD RES..2
(3525 4125);
FORCEPROP 1 LAST VALUE 68.1K
J 0
(3570 4200);
DISPLAY 0.617021 (3570 4200);
PAINT SKYBLUE (3570 4200);
FORCEPROP 1 LAST TOLERANCE 1%
J 0
(3570 4150);
DISPLAY 0.617021 (3570 4150);
PAINT SKYBLUE (3570 4150);
FORCEPROP 1 LAST LOCATION R7C25
J 0
(3570 4250);
DISPLAY 0.617021 (3570 4250);
PAINT AQUA (3570 4250);
FORCEPROP 1 LAST WATTAGE 1/16W
J 0
(3565 4100);
DISPLAY 0.617021 (3565 4100);
PAINT SKYBLUE (3565 4100);
FORCEPROP 1 LAST MATERIAL EMPTY
J 0
(3565 4050);
DISPLAY 0.617021 (3565 4050);
PAINT RED (3565 4050);
FORCEPROP 1 LAST PART_NUMBER G21796-187
J 0
(3565 4000);
DISPLAY 0.617021 (3565 4000);
PAINT BLUE (3565 4000);
FORCEPROP 1 LAST PACK_TYPE 0402
J 0
(3565 3950);
DISPLAY 0.617021 (3565 3950);
PAINT SKYBLUE (3565 3950);
FORCEPROP 1 LASTPIN (3525 4025) $PN 2
J 0
(3530 4035);
DISPLAY 0.787234 (3530 4035);
PAINT ORANGE (3530 4035);
DISPLAY INVISIBLE (3530 4035);
FORCEPROP 2 LAST CDS_LIB mstr_discrete
J 0
(3525 4125);
PAINT ORANGE (3525 4125);
DISPLAY INVISIBLE (3525 4125);
FORCEPROP 1 LASTPIN (3525 4225) $PN 1
J 0
(3530 4187);
DISPLAY 0.787234 (3530 4187);
PAINT ORANGE (3530 4187);
DISPLAY INVISIBLE (3530 4187);
FORCEPROP 2 LAST CDS_SEC 1
J 0
(3575 4350);
PAINT MONO (3575 4350);
DISPLAY INVISIBLE (3575 4350);
FORCEPROP 2 LAST $SEC 1
J 0
(3575 4350);
PAINT MONO (3575 4350);
DISPLAY INVISIBLE (3575 4350);
FORCEPROP 1 LAST PATH I103
J 0
(3575 4300);
DISPLAY 0.978723 (3575 4300);
PAINT WHITE (3575 4300);
DISPLAY INVISIBLE (3575 4300);
FORCEADD SHUNT..1
(-1300 1850);
FORCEPROP 1 LASTPIN (-1150 1850) $PN 2
J 0
(-1190 1860);
DISPLAY 0.617021 (-1190 1860);
PAINT ORANGE (-1190 1860);
FORCEPROP 1 LASTPIN (-1450 1850) $PN 1
J 2
(-1400 1860);
DISPLAY 0.617021 (-1400 1860);
PAINT ORANGE (-1400 1860);
FORCEPROP 1 LAST PART_NUMBER N_A
J 0
(-1375 1760);
DISPLAY 0.617021 (-1375 1760);
PAINT BLUE (-1375 1760);
FORCEPROP 1 LAST LOCATION SH3P1
J 0
(-1375 1900);
DISPLAY 0.617021 (-1375 1900);
PAINT AQUA (-1375 1900);
FORCEPROP 2 LAST SEC_TYPE SH0201
J 0
(-1350 2000);
DISPLAY 1.021277 (-1350 2000);
PAINT ORANGE (-1350 2000);
DISPLAY INVISIBLE (-1350 2000);
FORCEPROP 0 LAST SEC 1
J 0
(-1375 1950);
DISPLAY 0.680851 (-1375 1950);
PAINT MONO (-1375 1950);
DISPLAY INVISIBLE (-1375 1950);
FORCEPROP 1 LAST PATH I104
J 0
(-1350 1950);
DISPLAY 0.978723 (-1350 1950);
PAINT ORANGE (-1350 1950);
DISPLAY INVISIBLE (-1350 1950);
FORCEPROP 2 LAST CDS_LIB mstr_misc
J 0
(-1300 1850);
PAINT ORANGE (-1300 1850);
DISPLAY INVISIBLE (-1300 1850);
FORCEPROP 1 LAST PIN_SHORT A:B
J 0
(-1375 1600);
DISPLAY 1.021277 (-1375 1600);
PAINT ORANGE (-1375 1600);
DISPLAY INVISIBLE (-1375 1600);
FORCEPROP 1 LAST PACK_TYPE SH0201
J 0
(-1360 1665);
DISPLAY 0.978723 (-1360 1665);
PAINT SKYBLUE (-1360 1665);
DISPLAY INVISIBLE (-1360 1665);
FORCEPROP 1 LAST MATERIAL EMPTY
J 0
(-1375 1715);
DISPLAY 0.978723 (-1375 1715);
PAINT RED (-1375 1715);
DISPLAY INVISIBLE (-1375 1715);
FORCEADD SHUNT..1
(-1300 1400);
FORCEPROP 1 LASTPIN (-1450 1400) $PN 1
J 2
(-1400 1410);
DISPLAY 0.617021 (-1400 1410);
PAINT ORANGE (-1400 1410);
FORCEPROP 1 LASTPIN (-1150 1400) $PN 2
J 0
(-1190 1410);
DISPLAY 0.617021 (-1190 1410);
PAINT ORANGE (-1190 1410);
FORCEPROP 1 LAST LOCATION SH3P2
J 0
(-1375 1450);
DISPLAY 0.617021 (-1375 1450);
PAINT AQUA (-1375 1450);
FORCEPROP 1 LAST PART_NUMBER N_A
J 0
(-1375 1310);
DISPLAY 0.617021 (-1375 1310);
PAINT BLUE (-1375 1310);
FORCEPROP 2 LAST SEC_TYPE SH0201
J 0
(-1350 1550);
DISPLAY 1.021277 (-1350 1550);
PAINT ORANGE (-1350 1550);
DISPLAY INVISIBLE (-1350 1550);
FORCEPROP 1 LAST PATH I105
J 0
(-1350 1500);
DISPLAY 0.978723 (-1350 1500);
PAINT ORANGE (-1350 1500);
DISPLAY INVISIBLE (-1350 1500);
FORCEPROP 0 LAST SEC 1
J 0
(-1375 1500);
DISPLAY 0.680851 (-1375 1500);
PAINT MONO (-1375 1500);
DISPLAY INVISIBLE (-1375 1500);
FORCEPROP 2 LAST CDS_LIB mstr_misc
J 0
(-1300 1400);
PAINT ORANGE (-1300 1400);
DISPLAY INVISIBLE (-1300 1400);
FORCEPROP 1 LAST MATERIAL EMPTY
J 0
(-1375 1265);
DISPLAY 0.978723 (-1375 1265);
PAINT RED (-1375 1265);
DISPLAY INVISIBLE (-1375 1265);
FORCEPROP 1 LAST PACK_TYPE SH0201
J 0
(-1360 1215);
DISPLAY 0.978723 (-1360 1215);
PAINT SKYBLUE (-1360 1215);
DISPLAY INVISIBLE (-1360 1215);
FORCEPROP 1 LAST PIN_SHORT A:B
J 0
(-1375 1150);
DISPLAY 1.021277 (-1375 1150);
PAINT ORANGE (-1375 1150);
DISPLAY INVISIBLE (-1375 1150);
FORCEADD CAP_A..1
(450 3450);
FORCEPROP 0 LAST POP NOPOP
J 0
(225 3375);
DISPLAY 1.021277 (225 3375);
PAINT RED (225 3375);
FORCEPROP 1 LAST VALUE 0.1UF
J 0
(500 3500);
DISPLAY 0.617021 (500 3500);
PAINT SKYBLUE (500 3500);
FORCEPROP 1 LAST VOLTAGE 16V
J 0
(500 3450);
DISPLAY 0.617021 (500 3450);
PAINT SKYBLUE (500 3450);
FORCEPROP 1 LAST LOCATION CT70
J 0
(575 3450);
DISPLAY 0.617021 (575 3450);
PAINT AQUA (575 3450);
FORCEPROP 1 LAST TOLERANCE 10%
J 0
(500 3400);
DISPLAY 0.617021 (500 3400);
PAINT SKYBLUE (500 3400);
FORCEPROP 1 LAST MATERIAL X7R
J 0
(500 3350);
DISPLAY 0.617021 (500 3350);
PAINT SKYBLUE (500 3350);
FORCEPROP 1 LAST PART_NUMBER A36096-030
J 0
(500 3300);
DISPLAY 0.617021 (500 3300);
PAINT BLUE (500 3300);
FORCEPROP 1 LAST PACK_TYPE 0402V
J 0
(500 3250);
DISPLAY 0.617021 (500 3250);
PAINT SKYBLUE (500 3250);
FORCEPROP 2 LAST ROOM PVCCIN_CPU0_PWR_VR
J 0
(500 3600);
DISPLAY 1.361702 (500 3600);
PAINT ORANGE (500 3600);
DISPLAY INVISIBLE (500 3600);
FORCEPROP 1 LAST PATH I106
J 0
(500 3600);
DISPLAY 0.978723 (500 3600);
PAINT WHITE (500 3600);
DISPLAY INVISIBLE (500 3600);
FORCEPROP 2 LAST CDS_LIB dev_discrete
J 0
(450 3450);
PAINT MONO (450 3450);
DISPLAY INVISIBLE (450 3450);
FORCEPROP 1 LASTPIN (450 3550) $PN 1
J 0
(460 3530);
DISPLAY 0.787234 (460 3530);
PAINT ORANGE (460 3530);
DISPLAY INVISIBLE (460 3530);
FORCEPROP 1 LASTPIN (450 3350) $PN 2
J 0
(460 3330);
DISPLAY 0.787234 (460 3330);
PAINT ORANGE (460 3330);
DISPLAY INVISIBLE (460 3330);
FORCEADD GND..1
(450 3200);
FORCEPROP 3 LASTPIN (450 3250) SIG_NAME GND\g
J 0
(460 3260);
DISPLAY 0.659574 (460 3260);
PAINT MONO (460 3260);
DISPLAY INVISIBLE (460 3260);
FORCEPROP 2 LAST ROOM PVCCIN_CPU0_PWR_VR
J 0
(-100 3275);
DISPLAY 1.936170 (-100 3275);
PAINT ORANGE (-100 3275);
DISPLAY INVISIBLE (-100 3275);
FORCEPROP 2 LAST BOM_COST PROC_VRD_VCCIN_CPU0
J 0
(75 3275);
DISPLAY 1.446809 (75 3275);
PAINT MONO (75 3275);
DISPLAY INVISIBLE (75 3275);
FORCEPROP 1 LAST SIZE 1B
J 0
(525 3150);
DISPLAY 1.723404 (525 3150);
PAINT GREEN (525 3150);
DISPLAY INVISIBLE (525 3150);
FORCEPROP 1 LAST VOLTAGE 0
J 0
(450 3200);
PAINT SKYBLUE (450 3200);
DISPLAY INVISIBLE (450 3200);
FORCEPROP 1 LAST PATH I107
J 0
(525 3200);
DISPLAY 0.872340 (525 3200);
PAINT AQUA (525 3200);
DISPLAY INVISIBLE (525 3200);
FORCEPROP 2 LAST CDS_LIB mstr_symbols
J 0
(450 3200);
PAINT MONO (450 3200);
DISPLAY INVISIBLE (450 3200);
FORCEPROP 1 LAST BODY_TYPE PLUMBING
J 0
(405 3157);
DISPLAY 0.340426 (405 3157);
PAINT GREEN (405 3157);
DISPLAY INVISIBLE (405 3157);
FORCEPROP 1 LAST HDL_POWER GND
J 0
(450 3350);
DISPLAY 1.723404 (450 3350);
PAINT GREEN (450 3350);
DISPLAY INVISIBLE (450 3350);
FORCEADD CAP..1
(2375 3975);
FORCEPROP 1 LAST VALUE 1000PF
J 0
(2425 4025);
DISPLAY 0.617021 (2425 4025);
PAINT SKYBLUE (2425 4025);
FORCEPROP 1 LAST LOCATION CT71
J 0
(2425 4075);
DISPLAY 0.617021 (2425 4075);
PAINT AQUA (2425 4075);
FORCEPROP 1 LAST VOLTAGE 50V
J 0
(2425 3975);
DISPLAY 0.617021 (2425 3975);
PAINT SKYBLUE (2425 3975);
FORCEPROP 1 LAST TOLERANCE 10%
J 0
(2425 3925);
DISPLAY 0.617021 (2425 3925);
PAINT SKYBLUE (2425 3925);
FORCEPROP 1 LAST PACK_TYPE 0402LF
J 0
(2425 3775);
DISPLAY 0.617021 (2425 3775);
PAINT SKYBLUE (2425 3775);
FORCEPROP 0 LAST POP NOPOP
J 0
(2500 3950);
DISPLAY 1.021277 (2500 3950);
PAINT RED (2500 3950);
FORCEPROP 1 LAST PART_NUMBER A36096-046
J 0
(2425 3825);
DISPLAY 0.617021 (2425 3825);
PAINT BLUE (2425 3825);
FORCEPROP 1 LAST MATERIAL X7R
J 0
(2425 3875);
DISPLAY 0.617021 (2425 3875);
PAINT SKYBLUE (2425 3875);
FORCEPROP 0 LAST ROOM VDDQ_KLM_PWR_VR
J 0
(2425 4175);
DISPLAY 1.021277 (2425 4175);
PAINT ORANGE (2425 4175);
DISPLAY INVISIBLE (2425 4175);
FORCEPROP 1 LAST PATH I109
J 0
(2425 4125);
DISPLAY 0.978723 (2425 4125);
PAINT WHITE (2425 4125);
DISPLAY INVISIBLE (2425 4125);
FORCEPROP 2 LAST CDS_LIB mstr_discrete
J 0
(2375 3975);
PAINT MONO (2375 3975);
DISPLAY INVISIBLE (2375 3975);
FORCEPROP 1 LASTPIN (2375 3875) $PN 2
J 0
(2385 3855);
DISPLAY 0.787234 (2385 3855);
PAINT ORANGE (2385 3855);
DISPLAY INVISIBLE (2385 3855);
FORCEPROP 1 LASTPIN (2375 4075) $PN 1
J 0
(2385 4055);
DISPLAY 0.787234 (2385 4055);
PAINT ORANGE (2385 4055);
DISPLAY INVISIBLE (2385 4055);
FORCEADD GND..1
(2375 3750);
FORCEPROP 3 LASTPIN (2375 3800) SIG_NAME GND\g
J 0
(2385 3810);
DISPLAY 0.659574 (2385 3810);
PAINT MONO (2385 3810);
DISPLAY INVISIBLE (2385 3810);
FORCEPROP 2 LAST ROOM VDDQ_KLM_PWR_VR
J 0
(1800 3825);
DISPLAY 1.361702 (1800 3825);
PAINT ORANGE (1800 3825);
DISPLAY INVISIBLE (1800 3825);
FORCEPROP 1 LAST VOLTAGE 0
J 0
(2375 3750);
PAINT SKYBLUE (2375 3750);
DISPLAY INVISIBLE (2375 3750);
FORCEPROP 1 LAST SIZE 1B
J 0
(2450 3700);
DISPLAY 1.170213 (2450 3700);
PAINT AQUA (2450 3700);
DISPLAY INVISIBLE (2450 3700);
FORCEPROP 1 LAST PATH I110
J 0
(2450 3750);
DISPLAY 0.872340 (2450 3750);
PAINT AQUA (2450 3750);
DISPLAY INVISIBLE (2450 3750);
FORCEPROP 2 LAST CDS_LIB mstr_symbols
J 0
(2375 3750);
PAINT MONO (2375 3750);
DISPLAY INVISIBLE (2375 3750);
FORCEPROP 1 LAST BODY_TYPE PLUMBING
J 0
(2330 3707);
DISPLAY 0.340426 (2330 3707);
PAINT GREEN (2330 3707);
DISPLAY INVISIBLE (2330 3707);
FORCEPROP 1 LAST HDL_POWER GND
J 0
(2375 3900);
DISPLAY 1.170213 (2375 3900);
PAINT GREEN (2375 3900);
DISPLAY INVISIBLE (2375 3900);
FORCEADD GND..1
(2625 2900);
FORCEPROP 3 LASTPIN (2625 2950) SIG_NAME GND\g
J 0
(2635 2960);
DISPLAY 0.659574 (2635 2960);
PAINT MONO (2635 2960);
DISPLAY INVISIBLE (2635 2960);
FORCEPROP 2 LAST ROOM PVCCIN_CPU0_PWR_VR
J 0
(2075 2975);
DISPLAY 1.936170 (2075 2975);
PAINT ORANGE (2075 2975);
DISPLAY INVISIBLE (2075 2975);
FORCEPROP 2 LAST BOM_COST PROC_VRD_VCCIN_CPU0
J 0
(2250 2975);
DISPLAY 1.446809 (2250 2975);
PAINT MONO (2250 2975);
DISPLAY INVISIBLE (2250 2975);
FORCEPROP 1 LAST VOLTAGE 0
J 0
(2625 2900);
PAINT SKYBLUE (2625 2900);
DISPLAY INVISIBLE (2625 2900);
FORCEPROP 1 LAST SIZE 1B
J 0
(2700 2850);
DISPLAY 1.723404 (2700 2850);
PAINT GREEN (2700 2850);
DISPLAY INVISIBLE (2700 2850);
FORCEPROP 1 LAST PATH I113
J 0
(2700 2900);
DISPLAY 0.872340 (2700 2900);
PAINT AQUA (2700 2900);
DISPLAY INVISIBLE (2700 2900);
FORCEPROP 2 LAST CDS_LIB mstr_symbols
J 0
(2625 2900);
PAINT MONO (2625 2900);
DISPLAY INVISIBLE (2625 2900);
FORCEPROP 1 LAST BODY_TYPE PLUMBING
J 0
(2580 2857);
DISPLAY 0.340426 (2580 2857);
PAINT GREEN (2580 2857);
DISPLAY INVISIBLE (2580 2857);
FORCEPROP 1 LAST HDL_POWER GND
J 0
(2625 3050);
DISPLAY 1.723404 (2625 3050);
PAINT GREEN (2625 3050);
DISPLAY INVISIBLE (2625 3050);
FORCEADD CAP..1
(2625 3450);
FORCEPROP 1 LAST LOCATION CT72
J 0
(2675 3550);
DISPLAY 0.617021 (2675 3550);
PAINT AQUA (2675 3550);
FORCEPROP 0 LAST POP NOPOP
J 0
(2425 3475);
DISPLAY 0.808511 (2425 3475);
PAINT RED (2425 3475);
FORCEPROP 1 LASTPIN (2625 3350) $PN 2
J 0
(2635 3330);
DISPLAY 0.787234 (2635 3330);
PAINT ORANGE (2635 3330);
FORCEPROP 1 LAST PACK_TYPE 0402LF
J 0
(2675 3250);
DISPLAY 0.617021 (2675 3250);
PAINT SKYBLUE (2675 3250);
FORCEPROP 1 LAST PART_NUMBER A36096-046
J 0
(2675 3300);
DISPLAY 0.617021 (2675 3300);
PAINT BLUE (2675 3300);
FORCEPROP 1 LAST MATERIAL X7R
J 0
(2675 3350);
DISPLAY 0.617021 (2675 3350);
PAINT SKYBLUE (2675 3350);
FORCEPROP 1 LAST TOLERANCE 10%
J 0
(2675 3400);
DISPLAY 0.617021 (2675 3400);
PAINT SKYBLUE (2675 3400);
FORCEPROP 1 LAST VOLTAGE 50V
J 0
(2675 3450);
DISPLAY 0.617021 (2675 3450);
PAINT SKYBLUE (2675 3450);
FORCEPROP 1 LAST VALUE 1000PF
J 0
(2675 3500);
DISPLAY 0.617021 (2675 3500);
PAINT SKYBLUE (2675 3500);
FORCEPROP 1 LASTPIN (2625 3550) $PN 1
J 0
(2635 3530);
DISPLAY 0.787234 (2635 3530);
PAINT ORANGE (2635 3530);
FORCEPROP 2 LAST SEC_TYPE 0402LF
J 0
(2675 3650);
DISPLAY 1.021277 (2675 3650);
PAINT ORANGE (2675 3650);
DISPLAY INVISIBLE (2675 3650);
FORCEPROP 0 LAST SEC 1
J 0
(2675 3600);
DISPLAY 0.680851 (2675 3600);
PAINT MONO (2675 3600);
DISPLAY INVISIBLE (2675 3600);
FORCEPROP 0 LAST ROOM VDDQ_KLM_PWR_VR
J 0
(2675 3650);
DISPLAY 1.021277 (2675 3650);
PAINT ORANGE (2675 3650);
DISPLAY INVISIBLE (2675 3650);
FORCEPROP 1 LAST PATH I118
J 0
(2675 3600);
DISPLAY 0.978723 (2675 3600);
PAINT WHITE (2675 3600);
DISPLAY INVISIBLE (2675 3600);
FORCEPROP 2 LAST CDS_LIB mstr_discrete
J 0
(2625 3450);
PAINT MONO (2625 3450);
DISPLAY INVISIBLE (2625 3450);
FORCEADD RES..1
(-475 3750);
FORCEPROP 1 LASTPIN (-575 3750) $PN 1
J 0
(-563 3762);
DISPLAY 0.787234 (-563 3762);
PAINT ORANGE (-563 3762);
FORCEPROP 1 LAST LOCATION RT47
J 0
(-525 3675);
DISPLAY 0.617021 (-525 3675);
PAINT AQUA (-525 3675);
FORCEPROP 1 LAST PACK_TYPE 0603
J 0
(-525 3525);
DISPLAY 0.617021 (-525 3525);
PAINT SKYBLUE (-525 3525);
FORCEPROP 1 LAST VALUE 0
J 2
(-475 3625);
DISPLAY 0.617021 (-475 3625);
PAINT SKYBLUE (-475 3625);
FORCEPROP 1 LAST TOLERANCE 5.0%
J 0
(-250 3675);
DISPLAY 0.617021 (-250 3675);
PAINT SKYBLUE (-250 3675);
FORCEPROP 1 LAST MATERIAL CHIP
J 0
(-250 3625);
DISPLAY 0.617021 (-250 3625);
PAINT SKYBLUE (-250 3625);
FORCEPROP 1 LAST PART_NUMBER G22178-002
J 0
(-600 3575);
DISPLAY 0.617021 (-600 3575);
PAINT BLUE (-600 3575);
FORCEPROP 1 LAST WATTAGE 1/10W
J 2
(-125 3575);
DISPLAY 0.617021 (-125 3575);
PAINT SKYBLUE (-125 3575);
FORCEPROP 1 LASTPIN (-375 3750) $PN 2
J 0
(-413 3762);
DISPLAY 0.787234 (-413 3762);
PAINT ORANGE (-413 3762);
FORCEPROP 2 LAST SEC_TYPE 0603
J 0
(-525 3950);
DISPLAY 1.021277 (-525 3950);
PAINT ORANGE (-525 3950);
DISPLAY INVISIBLE (-525 3950);
FORCEPROP 0 LAST SEC 1
J 0
(-725 3850);
DISPLAY 0.680851 (-725 3850);
PAINT MONO (-725 3850);
DISPLAY INVISIBLE (-725 3850);
FORCEPROP 0 LAST BOM_COST NT_GBE_BASE
J 0
(-375 3975);
DISPLAY 1.021277 (-375 3975);
PAINT ORANGE (-375 3975);
DISPLAY INVISIBLE (-375 3975);
FORCEPROP 0 LAST ROOM NIC_SPRV
J 0
(-375 3875);
DISPLAY 1.021277 (-375 3875);
PAINT ORANGE (-375 3875);
DISPLAY INVISIBLE (-375 3875);
FORCEPROP 1 LAST PATH I120
J 0
(-525 3900);
DISPLAY 0.978723 (-525 3900);
PAINT WHITE (-525 3900);
DISPLAY INVISIBLE (-525 3900);
FORCEPROP 2 LAST CDS_LIB mstr_discrete
J 0
(-475 3750);
PAINT MONO (-475 3750);
DISPLAY INVISIBLE (-475 3750);
FORCEADD SC22U16V5MX-4-GP..1
(2900 2175);
FORCEPROP 1 LAST LOCATION C22W33
J 0
(3000 2310);
DISPLAY 0.617021 (3000 2310);
PAINT GREEN (3000 2310);
FORCEPROP 2 LAST PACK_SIZE 0805
J 0
(3000 2050);
DISPLAY 0.638298 (3000 2050);
PAINT GREEN (3000 2050);
FORCEPROP 2 LAST TYPE X6S
J 0
(3000 2100);
DISPLAY 0.638298 (3000 2100);
PAINT GREEN (3000 2100);
FORCEPROP 2 LAST RATED 16V
J 0
(3000 2150);
DISPLAY 0.638298 (3000 2150);
PAINT GREEN (3000 2150);
FORCEPROP 2 LAST TOLERANCE 20%
J 0
(3000 2200);
DISPLAY 0.638298 (3000 2200);
PAINT GREEN (3000 2200);
FORCEPROP 2 LAST ATTRIBUTE 22UF
J 0
(3000 2250);
DISPLAY 0.638298 (3000 2250);
PAINT GREEN (3000 2250);
FORCEPROP 2 LASTPIN (2900 2250) $PN 1
R 1
J 0
(2890 2260);
DISPLAY 0.808511 (2890 2260);
PAINT ORANGE (2890 2260);
FORCEPROP 2 LASTPIN (2900 2100) $PN 2
R 1
J 2
(2890 2090);
DISPLAY 0.808511 (2890 2090);
PAINT ORANGE (2890 2090);
FORCEPROP 1 LAST VALUE SC22U16V5MX-4-GP
R 1
J 0
(2975 1970);
DISPLAY 0.617021 (2975 1970);
PAINT GREEN (2975 1970);
FORCEPROP 1 LAST CDS_LMAN_SYM_OUTLINE -50,25,50,-25
J 0
(2900 2175);
DISPLAY 0.468085 (2900 2175);
PAINT GREEN (2900 2175);
DISPLAY INVISIBLE (2900 2175);
FORCEPROP 2 LAST CDS_LIB w_hdl
J 0
(2900 2175);
PAINT MONO (2900 2175);
DISPLAY INVISIBLE (2900 2175);
FORCEPROP 1 LAST PART_NUMBER 078.22611.0811
J 0
(2900 2175);
DISPLAY 0.617021 (2900 2175);
PAINT GREEN (2900 2175);
DISPLAY INVISIBLE (2900 2175);
FORCEPROP 2 LAST SEC_TYPE SMD-BCG5
J 0
(2925 2250);
DISPLAY 1.021277 (2925 2250);
PAINT ORANGE (2925 2250);
DISPLAY INVISIBLE (2925 2250);
FORCEPROP 2 LAST SEC 1
J 0
(2925 2250);
DISPLAY 0.680851 (2925 2250);
PAINT MONO (2925 2250);
DISPLAY INVISIBLE (2925 2250);
FORCEPROP 1 LAST PACK_TYPE SMD-BCG5
J 0
(2900 2175);
DISPLAY 0.617021 (2900 2175);
PAINT GREEN (2900 2175);
DISPLAY INVISIBLE (2900 2175);
FORCEPROP 1 LAST PATH I124
J 0
(2900 2175);
DISPLAY 0.617021 (2900 2175);
PAINT GREEN (2900 2175);
DISPLAY INVISIBLE (2900 2175);
FORCEADD GND..1
(2900 1950);
FORCEPROP 3 LASTPIN (2900 2000) SIG_NAME GND\g
J 0
(2910 2010);
DISPLAY 0.659574 (2910 2010);
PAINT MONO (2910 2010);
DISPLAY INVISIBLE (2910 2010);
FORCEPROP 1 LAST SIZE 1B
J 0
(2975 1900);
DISPLAY 0.872340 (2975 1900);
PAINT GREEN (2975 1900);
DISPLAY INVISIBLE (2975 1900);
FORCEPROP 1 LAST VOLTAGE 0
J 0
(2900 1950);
PAINT SKYBLUE (2900 1950);
DISPLAY INVISIBLE (2900 1950);
FORCEPROP 2 LAST ROOM PVPP_KLM_VR
J 0
(2325 2025);
DISPLAY 1.042553 (2325 2025);
PAINT GREEN (2325 2025);
DISPLAY INVISIBLE (2325 2025);
FORCEPROP 2 LAST BOM_COST PVPP_KLM_VR
J 0
(2050 2025);
DISPLAY 1.042553 (2050 2025);
PAINT WHITE (2050 2025);
DISPLAY INVISIBLE (2050 2025);
FORCEPROP 2 LAST CDS_LIB mstr_symbols
J 0
(2900 1950);
PAINT MONO (2900 1950);
DISPLAY INVISIBLE (2900 1950);
FORCEPROP 1 LAST PATH I125
J 0
(2975 1950);
DISPLAY 0.872340 (2975 1950);
PAINT AQUA (2975 1950);
DISPLAY INVISIBLE (2975 1950);
FORCEPROP 1 LAST BODY_TYPE PLUMBING
J 0
(2855 1907);
DISPLAY 0.340426 (2855 1907);
PAINT GREEN (2855 1907);
DISPLAY INVISIBLE (2855 1907);
FORCEPROP 1 LAST HDL_POWER GND
J 0
(2900 2100);
DISPLAY 0.872340 (2900 2100);
PAINT GREEN (2900 2100);
DISPLAY INVISIBLE (2900 2100);
FORCEADD SC22U16V5MX-4-GP..1
(2600 2175);
FORCEPROP 2 LAST ATTRIBUTE 22UF
J 0
(2700 2250);
DISPLAY 0.638298 (2700 2250);
PAINT GREEN (2700 2250);
FORCEPROP 1 LAST LOCATION C22W32
J 0
(2700 2310);
DISPLAY 0.617021 (2700 2310);
PAINT GREEN (2700 2310);
FORCEPROP 2 LASTPIN (2600 2100) $PN 2
R 1
J 2
(2590 2090);
DISPLAY 0.808511 (2590 2090);
PAINT ORANGE (2590 2090);
FORCEPROP 2 LASTPIN (2600 2250) $PN 1
R 1
J 0
(2590 2260);
DISPLAY 0.808511 (2590 2260);
PAINT ORANGE (2590 2260);
FORCEPROP 2 LAST TOLERANCE 20%
J 0
(2700 2200);
DISPLAY 0.638298 (2700 2200);
PAINT GREEN (2700 2200);
FORCEPROP 2 LAST RATED 16V
J 0
(2700 2150);
DISPLAY 0.638298 (2700 2150);
PAINT GREEN (2700 2150);
FORCEPROP 2 LAST TYPE X6S
J 0
(2700 2100);
DISPLAY 0.638298 (2700 2100);
PAINT GREEN (2700 2100);
FORCEPROP 2 LAST PACK_SIZE 0805
J 0
(2700 2050);
DISPLAY 0.638298 (2700 2050);
PAINT GREEN (2700 2050);
FORCEPROP 1 LAST VALUE SC22U16V5MX-4-GP
R 1
J 0
(2675 1970);
DISPLAY 0.617021 (2675 1970);
PAINT GREEN (2675 1970);
FORCEPROP 1 LAST PATH I126
J 0
(2600 2175);
DISPLAY 0.617021 (2600 2175);
PAINT GREEN (2600 2175);
DISPLAY INVISIBLE (2600 2175);
FORCEPROP 1 LAST PACK_TYPE SMD-BCG5
J 0
(2600 2175);
DISPLAY 0.617021 (2600 2175);
PAINT GREEN (2600 2175);
DISPLAY INVISIBLE (2600 2175);
FORCEPROP 2 LAST SEC 1
J 0
(2625 2250);
DISPLAY 0.680851 (2625 2250);
PAINT MONO (2625 2250);
DISPLAY INVISIBLE (2625 2250);
FORCEPROP 2 LAST SEC_TYPE SMD-BCG5
J 0
(2625 2250);
DISPLAY 1.021277 (2625 2250);
PAINT ORANGE (2625 2250);
DISPLAY INVISIBLE (2625 2250);
FORCEPROP 1 LAST PART_NUMBER 078.22611.0811
J 0
(2600 2175);
DISPLAY 0.617021 (2600 2175);
PAINT GREEN (2600 2175);
DISPLAY INVISIBLE (2600 2175);
FORCEPROP 2 LAST CDS_LIB w_hdl
J 0
(2600 2175);
PAINT MONO (2600 2175);
DISPLAY INVISIBLE (2600 2175);
FORCEPROP 1 LAST CDS_LMAN_SYM_OUTLINE -50,25,50,-25
J 0
(2600 2175);
DISPLAY 0.468085 (2600 2175);
PAINT GREEN (2600 2175);
DISPLAY INVISIBLE (2600 2175);
FORCEADD GND..1
(2300 1950);
FORCEPROP 3 LASTPIN (2300 2000) SIG_NAME GND\g
J 0
(2310 2010);
DISPLAY 0.659574 (2310 2010);
PAINT MONO (2310 2010);
DISPLAY INVISIBLE (2310 2010);
FORCEPROP 2 LAST CDS_LIB mstr_symbols
J 0
(2300 1950);
PAINT MONO (2300 1950);
DISPLAY INVISIBLE (2300 1950);
FORCEPROP 2 LAST BOM_COST PVPP_KLM_VR
J 0
(1450 2025);
DISPLAY 1.042553 (1450 2025);
PAINT WHITE (1450 2025);
DISPLAY INVISIBLE (1450 2025);
FORCEPROP 2 LAST ROOM PVPP_KLM_VR
J 0
(1725 2025);
DISPLAY 1.042553 (1725 2025);
PAINT GREEN (1725 2025);
DISPLAY INVISIBLE (1725 2025);
FORCEPROP 1 LAST VOLTAGE 0
J 0
(2300 1950);
PAINT SKYBLUE (2300 1950);
DISPLAY INVISIBLE (2300 1950);
FORCEPROP 1 LAST SIZE 1B
J 0
(2375 1900);
DISPLAY 0.872340 (2375 1900);
PAINT GREEN (2375 1900);
DISPLAY INVISIBLE (2375 1900);
FORCEPROP 1 LAST PATH I127
J 0
(2375 1950);
DISPLAY 0.872340 (2375 1950);
PAINT AQUA (2375 1950);
DISPLAY INVISIBLE (2375 1950);
FORCEPROP 1 LAST BODY_TYPE PLUMBING
J 0
(2255 1907);
DISPLAY 0.340426 (2255 1907);
PAINT GREEN (2255 1907);
DISPLAY INVISIBLE (2255 1907);
FORCEPROP 1 LAST HDL_POWER GND
J 0
(2300 2100);
DISPLAY 0.872340 (2300 2100);
PAINT GREEN (2300 2100);
DISPLAY INVISIBLE (2300 2100);
FORCEADD GND..1
(2600 1950);
FORCEPROP 3 LASTPIN (2600 2000) SIG_NAME GND\g
J 0
(2610 2010);
DISPLAY 0.659574 (2610 2010);
PAINT MONO (2610 2010);
DISPLAY INVISIBLE (2610 2010);
FORCEPROP 1 LAST PATH I128
J 0
(2675 1950);
DISPLAY 0.872340 (2675 1950);
PAINT AQUA (2675 1950);
DISPLAY INVISIBLE (2675 1950);
FORCEPROP 1 LAST SIZE 1B
J 0
(2675 1900);
DISPLAY 0.872340 (2675 1900);
PAINT GREEN (2675 1900);
DISPLAY INVISIBLE (2675 1900);
FORCEPROP 1 LAST VOLTAGE 0
J 0
(2600 1950);
PAINT SKYBLUE (2600 1950);
DISPLAY INVISIBLE (2600 1950);
FORCEPROP 2 LAST ROOM PVPP_KLM_VR
J 0
(2025 2025);
DISPLAY 1.042553 (2025 2025);
PAINT GREEN (2025 2025);
DISPLAY INVISIBLE (2025 2025);
FORCEPROP 2 LAST BOM_COST PVPP_KLM_VR
J 0
(1750 2025);
DISPLAY 1.042553 (1750 2025);
PAINT WHITE (1750 2025);
DISPLAY INVISIBLE (1750 2025);
FORCEPROP 2 LAST CDS_LIB mstr_symbols
J 0
(2600 1950);
PAINT MONO (2600 1950);
DISPLAY INVISIBLE (2600 1950);
FORCEPROP 1 LAST BODY_TYPE PLUMBING
J 0
(2555 1907);
DISPLAY 0.340426 (2555 1907);
PAINT GREEN (2555 1907);
DISPLAY INVISIBLE (2555 1907);
FORCEPROP 1 LAST HDL_POWER GND
J 0
(2600 2100);
DISPLAY 0.872340 (2600 2100);
PAINT GREEN (2600 2100);
DISPLAY INVISIBLE (2600 2100);
FORCEADD SC22U16V5MX-4-GP..1
(2300 2175);
FORCEPROP 2 LASTPIN (2300 2100) $PN 2
R 1
J 2
(2290 2090);
DISPLAY 0.808511 (2290 2090);
PAINT ORANGE (2290 2090);
FORCEPROP 2 LASTPIN (2300 2250) $PN 1
R 1
J 0
(2290 2260);
DISPLAY 0.808511 (2290 2260);
PAINT ORANGE (2290 2260);
FORCEPROP 2 LAST ATTRIBUTE 22UF
J 0
(2400 2250);
DISPLAY 0.638298 (2400 2250);
PAINT GREEN (2400 2250);
FORCEPROP 2 LAST TOLERANCE 20%
J 0
(2400 2200);
DISPLAY 0.638298 (2400 2200);
PAINT GREEN (2400 2200);
FORCEPROP 2 LAST RATED 16V
J 0
(2400 2150);
DISPLAY 0.638298 (2400 2150);
PAINT GREEN (2400 2150);
FORCEPROP 2 LAST TYPE X6S
J 0
(2400 2100);
DISPLAY 0.638298 (2400 2100);
PAINT GREEN (2400 2100);
FORCEPROP 2 LAST PACK_SIZE 0805
J 0
(2400 2050);
DISPLAY 0.638298 (2400 2050);
PAINT GREEN (2400 2050);
FORCEPROP 1 LAST VALUE SC22U16V5MX-4-GP
R 1
J 0
(2375 1970);
DISPLAY 0.617021 (2375 1970);
PAINT GREEN (2375 1970);
FORCEPROP 1 LAST LOCATION C22W31
J 0
(2400 2310);
DISPLAY 0.617021 (2400 2310);
PAINT GREEN (2400 2310);
FORCEPROP 1 LAST PATH I129
J 0
(2300 2175);
DISPLAY 0.617021 (2300 2175);
PAINT GREEN (2300 2175);
DISPLAY INVISIBLE (2300 2175);
FORCEPROP 1 LAST PACK_TYPE SMD-BCG5
J 0
(2300 2175);
DISPLAY 0.617021 (2300 2175);
PAINT GREEN (2300 2175);
DISPLAY INVISIBLE (2300 2175);
FORCEPROP 2 LAST SEC 1
J 0
(2325 2250);
DISPLAY 0.680851 (2325 2250);
PAINT MONO (2325 2250);
DISPLAY INVISIBLE (2325 2250);
FORCEPROP 2 LAST SEC_TYPE SMD-BCG5
J 0
(2325 2250);
DISPLAY 1.021277 (2325 2250);
PAINT ORANGE (2325 2250);
DISPLAY INVISIBLE (2325 2250);
FORCEPROP 1 LAST PART_NUMBER 078.22611.0811
J 0
(2300 2175);
DISPLAY 0.617021 (2300 2175);
PAINT GREEN (2300 2175);
DISPLAY INVISIBLE (2300 2175);
FORCEPROP 2 LAST CDS_LIB w_hdl
J 0
(2300 2175);
PAINT MONO (2300 2175);
DISPLAY INVISIBLE (2300 2175);
FORCEPROP 1 LAST CDS_LMAN_SYM_OUTLINE -50,25,50,-25
J 0
(2300 2175);
DISPLAY 0.468085 (2300 2175);
PAINT GREEN (2300 2175);
DISPLAY INVISIBLE (2300 2175);
FORCEADD GND..1
(850 950);
FORCEPROP 3 LASTPIN (850 1000) SIG_NAME GND\g
J 0
(860 1010);
DISPLAY 0.659574 (860 1010);
PAINT MONO (860 1010);
DISPLAY INVISIBLE (860 1010);
FORCEPROP 1 LAST SIZE 1B
J 0
(925 900);
DISPLAY 0.638298 (925 900);
PAINT GREEN (925 900);
DISPLAY INVISIBLE (925 900);
FORCEPROP 2 LAST BOM_COST PROC_VRD_PVCCIO_CPU0
J 0
(350 1025);
DISPLAY 0.723404 (350 1025);
PAINT ORANGE (350 1025);
DISPLAY INVISIBLE (350 1025);
FORCEPROP 2 LAST ROOM PVCCIO_CPU0
J 0
(550 1025);
DISPLAY 0.723404 (550 1025);
PAINT ORANGE (550 1025);
DISPLAY INVISIBLE (550 1025);
FORCEPROP 1 LAST VOLTAGE 0
J 0
(850 950);
DISPLAY 0.723404 (850 950);
PAINT SKYBLUE (850 950);
DISPLAY INVISIBLE (850 950);
FORCEPROP 2 LAST CDS_LIB mstr_symbols
J 0
(850 950);
DISPLAY 0.723404 (850 950);
PAINT ORANGE (850 950);
DISPLAY INVISIBLE (850 950);
FORCEPROP 1 LAST PATH I13
J 0
(925 950);
DISPLAY 0.872340 (925 950);
PAINT AQUA (925 950);
DISPLAY INVISIBLE (925 950);
FORCEPROP 1 LAST BODY_TYPE PLUMBING
J 0
(805 907);
DISPLAY 0.340426 (805 907);
PAINT GREEN (805 907);
DISPLAY INVISIBLE (805 907);
FORCEPROP 1 LAST HDL_POWER GND
J 0
(850 1100);
DISPLAY 0.638298 (850 1100);
PAINT GREEN (850 1100);
DISPLAY INVISIBLE (850 1100);
FORCEADD SC22U16V5MX-4-GP..1
(2000 2175);
FORCEPROP 2 LASTPIN (2000 2250) $PN 1
R 1
J 0
(1990 2260);
DISPLAY 0.808511 (1990 2260);
PAINT ORANGE (1990 2260);
FORCEPROP 2 LASTPIN (2000 2100) $PN 2
R 1
J 2
(1990 2090);
DISPLAY 0.808511 (1990 2090);
PAINT ORANGE (1990 2090);
FORCEPROP 1 LAST LOCATION C7C8
J 0
(2100 2310);
DISPLAY 0.617021 (2100 2310);
PAINT GREEN (2100 2310);
FORCEPROP 2 LAST ATTRIBUTE 22UF
J 0
(2100 2250);
DISPLAY 0.638298 (2100 2250);
PAINT GREEN (2100 2250);
FORCEPROP 2 LAST TOLERANCE 20%
J 0
(2100 2200);
DISPLAY 0.638298 (2100 2200);
PAINT GREEN (2100 2200);
FORCEPROP 2 LAST RATED 16V
J 0
(2100 2150);
DISPLAY 0.638298 (2100 2150);
PAINT GREEN (2100 2150);
FORCEPROP 2 LAST TYPE X6S
J 0
(2100 2100);
DISPLAY 0.638298 (2100 2100);
PAINT GREEN (2100 2100);
FORCEPROP 2 LAST PACK_SIZE 0805
J 0
(2100 2050);
DISPLAY 0.638298 (2100 2050);
PAINT GREEN (2100 2050);
FORCEPROP 1 LAST VALUE SC22U16V5MX-4-GP
R 1
J 0
(2075 1970);
DISPLAY 0.617021 (2075 1970);
PAINT GREEN (2075 1970);
FORCEPROP 1 LAST PATH I130
J 0
(2000 2175);
DISPLAY 0.617021 (2000 2175);
PAINT GREEN (2000 2175);
DISPLAY INVISIBLE (2000 2175);
FORCEPROP 1 LAST CDS_LMAN_SYM_OUTLINE -50,25,50,-25
J 0
(2000 2175);
DISPLAY 0.468085 (2000 2175);
PAINT GREEN (2000 2175);
DISPLAY INVISIBLE (2000 2175);
FORCEPROP 2 LAST CDS_LIB w_hdl
J 0
(2000 2175);
PAINT MONO (2000 2175);
DISPLAY INVISIBLE (2000 2175);
FORCEPROP 1 LAST PART_NUMBER 078.22611.0811
J 0
(2000 2175);
DISPLAY 0.617021 (2000 2175);
PAINT GREEN (2000 2175);
DISPLAY INVISIBLE (2000 2175);
FORCEPROP 2 LAST SEC_TYPE SMD-BCG5
J 0
(2025 2250);
DISPLAY 1.021277 (2025 2250);
PAINT ORANGE (2025 2250);
DISPLAY INVISIBLE (2025 2250);
FORCEPROP 2 LAST SEC 1
J 0
(2025 2250);
DISPLAY 0.680851 (2025 2250);
PAINT MONO (2025 2250);
DISPLAY INVISIBLE (2025 2250);
FORCEPROP 1 LAST PACK_TYPE SMD-BCG5
J 0
(2000 2175);
DISPLAY 0.617021 (2000 2175);
PAINT GREEN (2000 2175);
DISPLAY INVISIBLE (2000 2175);
FORCEADD GND..1
(2000 1950);
FORCEPROP 3 LASTPIN (2000 2000) SIG_NAME GND\g
J 0
(2010 2010);
DISPLAY 0.659574 (2010 2010);
PAINT MONO (2010 2010);
DISPLAY INVISIBLE (2010 2010);
FORCEPROP 2 LAST CDS_LIB mstr_symbols
J 0
(2000 1950);
PAINT MONO (2000 1950);
DISPLAY INVISIBLE (2000 1950);
FORCEPROP 2 LAST BOM_COST PVPP_KLM_VR
J 0
(1150 2025);
DISPLAY 1.042553 (1150 2025);
PAINT WHITE (1150 2025);
DISPLAY INVISIBLE (1150 2025);
FORCEPROP 2 LAST ROOM PVPP_KLM_VR
J 0
(1425 2025);
DISPLAY 1.042553 (1425 2025);
PAINT GREEN (1425 2025);
DISPLAY INVISIBLE (1425 2025);
FORCEPROP 1 LAST VOLTAGE 0
J 0
(2000 1950);
PAINT SKYBLUE (2000 1950);
DISPLAY INVISIBLE (2000 1950);
FORCEPROP 1 LAST SIZE 1B
J 0
(2075 1900);
DISPLAY 0.872340 (2075 1900);
PAINT GREEN (2075 1900);
DISPLAY INVISIBLE (2075 1900);
FORCEPROP 1 LAST PATH I131
J 0
(2075 1950);
DISPLAY 0.872340 (2075 1950);
PAINT AQUA (2075 1950);
DISPLAY INVISIBLE (2075 1950);
FORCEPROP 1 LAST BODY_TYPE PLUMBING
J 0
(1955 1907);
DISPLAY 0.340426 (1955 1907);
PAINT GREEN (1955 1907);
DISPLAY INVISIBLE (1955 1907);
FORCEPROP 1 LAST HDL_POWER GND
J 0
(2000 2100);
DISPLAY 0.872340 (2000 2100);
PAINT GREEN (2000 2100);
DISPLAY INVISIBLE (2000 2100);
FORCEADD SC22U16V5MX-4-GP..1
(1550 2175);
FORCEPROP 2 LASTPIN (1550 2250) $PN 1
R 1
J 0
(1540 2260);
DISPLAY 0.808511 (1540 2260);
PAINT ORANGE (1540 2260);
FORCEPROP 2 LASTPIN (1550 2100) $PN 2
R 1
J 2
(1540 2090);
DISPLAY 0.808511 (1540 2090);
PAINT ORANGE (1540 2090);
FORCEPROP 1 LAST LOCATION C22W30
J 0
(1650 2310);
DISPLAY 0.617021 (1650 2310);
PAINT GREEN (1650 2310);
FORCEPROP 2 LAST ATTRIBUTE 22UF
J 0
(1650 2250);
DISPLAY 0.638298 (1650 2250);
PAINT GREEN (1650 2250);
FORCEPROP 2 LAST TOLERANCE 20%
J 0
(1650 2200);
DISPLAY 0.638298 (1650 2200);
PAINT GREEN (1650 2200);
FORCEPROP 2 LAST TYPE X6S
J 0
(1650 2100);
DISPLAY 0.638298 (1650 2100);
PAINT GREEN (1650 2100);
FORCEPROP 2 LAST PACK_SIZE 0805
J 0
(1650 2050);
DISPLAY 0.638298 (1650 2050);
PAINT GREEN (1650 2050);
FORCEPROP 1 LAST VALUE SC22U16V5MX-4-GP
R 1
J 0
(1625 1970);
DISPLAY 0.617021 (1625 1970);
PAINT GREEN (1625 1970);
FORCEPROP 2 LAST RATED 16V
J 0
(1650 2150);
DISPLAY 0.638298 (1650 2150);
PAINT GREEN (1650 2150);
FORCEPROP 1 LAST CDS_LMAN_SYM_OUTLINE -50,25,50,-25
J 0
(1550 2175);
DISPLAY 0.468085 (1550 2175);
PAINT GREEN (1550 2175);
DISPLAY INVISIBLE (1550 2175);
FORCEPROP 2 LAST CDS_LIB w_hdl
J 0
(1550 2175);
PAINT MONO (1550 2175);
DISPLAY INVISIBLE (1550 2175);
FORCEPROP 1 LAST PART_NUMBER 078.22611.0811
J 0
(1550 2175);
DISPLAY 0.617021 (1550 2175);
PAINT GREEN (1550 2175);
DISPLAY INVISIBLE (1550 2175);
FORCEPROP 2 LAST SEC_TYPE SMD-BCG5
J 0
(1575 2250);
DISPLAY 1.021277 (1575 2250);
PAINT ORANGE (1575 2250);
DISPLAY INVISIBLE (1575 2250);
FORCEPROP 2 LAST SEC 1
J 0
(1575 2250);
DISPLAY 0.680851 (1575 2250);
PAINT MONO (1575 2250);
DISPLAY INVISIBLE (1575 2250);
FORCEPROP 1 LAST PACK_TYPE SMD-BCG5
J 0
(1550 2175);
DISPLAY 0.617021 (1550 2175);
PAINT GREEN (1550 2175);
DISPLAY INVISIBLE (1550 2175);
FORCEPROP 1 LAST PATH I132
J 0
(1550 2175);
DISPLAY 0.617021 (1550 2175);
PAINT GREEN (1550 2175);
DISPLAY INVISIBLE (1550 2175);
FORCEADD GND..1
(1550 1950);
FORCEPROP 3 LASTPIN (1550 2000) SIG_NAME GND\g
J 0
(1560 2010);
DISPLAY 0.659574 (1560 2010);
PAINT MONO (1560 2010);
DISPLAY INVISIBLE (1560 2010);
FORCEPROP 1 LAST PATH I133
J 0
(1625 1950);
DISPLAY 0.872340 (1625 1950);
PAINT AQUA (1625 1950);
DISPLAY INVISIBLE (1625 1950);
FORCEPROP 2 LAST CDS_LIB mstr_symbols
J 0
(1550 1950);
PAINT MONO (1550 1950);
DISPLAY INVISIBLE (1550 1950);
FORCEPROP 2 LAST BOM_COST PVPP_KLM_VR
J 0
(700 2025);
DISPLAY 1.042553 (700 2025);
PAINT WHITE (700 2025);
DISPLAY INVISIBLE (700 2025);
FORCEPROP 2 LAST ROOM PVPP_KLM_VR
J 0
(975 2025);
DISPLAY 1.042553 (975 2025);
PAINT GREEN (975 2025);
DISPLAY INVISIBLE (975 2025);
FORCEPROP 1 LAST VOLTAGE 0
J 0
(1550 1950);
PAINT SKYBLUE (1550 1950);
DISPLAY INVISIBLE (1550 1950);
FORCEPROP 1 LAST SIZE 1B
J 0
(1625 1900);
DISPLAY 0.872340 (1625 1900);
PAINT GREEN (1625 1900);
DISPLAY INVISIBLE (1625 1900);
FORCEPROP 1 LAST BODY_TYPE PLUMBING
J 0
(1505 1907);
DISPLAY 0.340426 (1505 1907);
PAINT GREEN (1505 1907);
DISPLAY INVISIBLE (1505 1907);
FORCEPROP 1 LAST HDL_POWER GND
J 0
(1550 2100);
DISPLAY 0.872340 (1550 2100);
PAINT GREEN (1550 2100);
DISPLAY INVISIBLE (1550 2100);
FORCEADD SC22U16V5MX-4-GP..1
(1250 2175);
FORCEPROP 2 LASTPIN (1250 2250) $PN 1
R 1
J 0
(1240 2260);
DISPLAY 0.808511 (1240 2260);
PAINT ORANGE (1240 2260);
FORCEPROP 2 LASTPIN (1250 2100) $PN 2
R 1
J 2
(1240 2090);
DISPLAY 0.808511 (1240 2090);
PAINT ORANGE (1240 2090);
FORCEPROP 2 LAST ATTRIBUTE 22UF
J 0
(1350 2250);
DISPLAY 0.638298 (1350 2250);
PAINT GREEN (1350 2250);
FORCEPROP 2 LAST TOLERANCE 20%
J 0
(1350 2200);
DISPLAY 0.638298 (1350 2200);
PAINT GREEN (1350 2200);
FORCEPROP 2 LAST RATED 16V
J 0
(1350 2150);
DISPLAY 0.638298 (1350 2150);
PAINT GREEN (1350 2150);
FORCEPROP 2 LAST PACK_SIZE 0805
J 0
(1350 2050);
DISPLAY 0.638298 (1350 2050);
PAINT GREEN (1350 2050);
FORCEPROP 2 LAST TYPE X6S
J 0
(1350 2100);
DISPLAY 0.638298 (1350 2100);
PAINT GREEN (1350 2100);
FORCEPROP 1 LAST LOCATION C22W29
J 0
(1350 2310);
DISPLAY 0.617021 (1350 2310);
PAINT GREEN (1350 2310);
FORCEPROP 1 LAST VALUE SC22U16V5MX-4-GP
R 1
J 0
(1325 1970);
DISPLAY 0.617021 (1325 1970);
PAINT GREEN (1325 1970);
FORCEPROP 1 LAST CDS_LMAN_SYM_OUTLINE -50,25,50,-25
J 0
(1250 2175);
DISPLAY 0.468085 (1250 2175);
PAINT GREEN (1250 2175);
DISPLAY INVISIBLE (1250 2175);
FORCEPROP 2 LAST CDS_LIB w_hdl
J 0
(1250 2175);
PAINT MONO (1250 2175);
DISPLAY INVISIBLE (1250 2175);
FORCEPROP 1 LAST PART_NUMBER 078.22611.0811
J 0
(1250 2175);
DISPLAY 0.617021 (1250 2175);
PAINT GREEN (1250 2175);
DISPLAY INVISIBLE (1250 2175);
FORCEPROP 2 LAST SEC_TYPE SMD-BCG5
J 0
(1275 2250);
DISPLAY 1.021277 (1275 2250);
PAINT ORANGE (1275 2250);
DISPLAY INVISIBLE (1275 2250);
FORCEPROP 2 LAST SEC 1
J 0
(1275 2250);
DISPLAY 0.680851 (1275 2250);
PAINT MONO (1275 2250);
DISPLAY INVISIBLE (1275 2250);
FORCEPROP 1 LAST PACK_TYPE SMD-BCG5
J 0
(1250 2175);
DISPLAY 0.617021 (1250 2175);
PAINT GREEN (1250 2175);
DISPLAY INVISIBLE (1250 2175);
FORCEPROP 1 LAST PATH I134
J 0
(1250 2175);
DISPLAY 0.617021 (1250 2175);
PAINT GREEN (1250 2175);
DISPLAY INVISIBLE (1250 2175);
FORCEADD GND..1
(1250 1950);
FORCEPROP 3 LASTPIN (1250 2000) SIG_NAME GND\g
J 0
(1260 2010);
DISPLAY 0.659574 (1260 2010);
PAINT MONO (1260 2010);
DISPLAY INVISIBLE (1260 2010);
FORCEPROP 1 LAST PATH I135
J 0
(1325 1950);
DISPLAY 0.872340 (1325 1950);
PAINT AQUA (1325 1950);
DISPLAY INVISIBLE (1325 1950);
FORCEPROP 1 LAST SIZE 1B
J 0
(1325 1900);
DISPLAY 0.872340 (1325 1900);
PAINT GREEN (1325 1900);
DISPLAY INVISIBLE (1325 1900);
FORCEPROP 1 LAST VOLTAGE 0
J 0
(1250 1950);
PAINT SKYBLUE (1250 1950);
DISPLAY INVISIBLE (1250 1950);
FORCEPROP 2 LAST ROOM PVPP_KLM_VR
J 0
(675 2025);
DISPLAY 1.042553 (675 2025);
PAINT GREEN (675 2025);
DISPLAY INVISIBLE (675 2025);
FORCEPROP 2 LAST BOM_COST PVPP_KLM_VR
J 0
(400 2025);
DISPLAY 1.042553 (400 2025);
PAINT WHITE (400 2025);
DISPLAY INVISIBLE (400 2025);
FORCEPROP 2 LAST CDS_LIB mstr_symbols
J 0
(1250 1950);
PAINT MONO (1250 1950);
DISPLAY INVISIBLE (1250 1950);
FORCEPROP 1 LAST BODY_TYPE PLUMBING
J 0
(1205 1907);
DISPLAY 0.340426 (1205 1907);
PAINT GREEN (1205 1907);
DISPLAY INVISIBLE (1205 1907);
FORCEPROP 1 LAST HDL_POWER GND
J 0
(1250 2100);
DISPLAY 0.872340 (1250 2100);
PAINT GREEN (1250 2100);
DISPLAY INVISIBLE (1250 2100);
FORCEADD SC22U16V5MX-4-GP..1
(950 2175);
FORCEPROP 2 LASTPIN (950 2250) $PN 1
R 1
J 0
(940 2260);
DISPLAY 0.808511 (940 2260);
PAINT ORANGE (940 2260);
FORCEPROP 1 LAST LOCATION C22W28
J 0
(1050 2310);
DISPLAY 0.617021 (1050 2310);
PAINT GREEN (1050 2310);
FORCEPROP 2 LAST ATTRIBUTE 22UF
J 0
(1050 2250);
DISPLAY 0.638298 (1050 2250);
PAINT GREEN (1050 2250);
FORCEPROP 2 LAST TOLERANCE 20%
J 0
(1050 2200);
DISPLAY 0.638298 (1050 2200);
PAINT GREEN (1050 2200);
FORCEPROP 2 LAST PACK_SIZE 0805
J 0
(1050 2050);
DISPLAY 0.638298 (1050 2050);
PAINT GREEN (1050 2050);
FORCEPROP 2 LAST RATED 16V
J 0
(1050 2150);
DISPLAY 0.638298 (1050 2150);
PAINT GREEN (1050 2150);
FORCEPROP 2 LAST TYPE X6S
J 0
(1050 2100);
DISPLAY 0.638298 (1050 2100);
PAINT GREEN (1050 2100);
FORCEPROP 1 LAST VALUE SC22U16V5MX-4-GP
R 1
J 0
(1025 1970);
DISPLAY 0.617021 (1025 1970);
PAINT GREEN (1025 1970);
FORCEPROP 2 LASTPIN (950 2100) $PN 2
R 1
J 2
(940 2090);
DISPLAY 0.808511 (940 2090);
PAINT ORANGE (940 2090);
FORCEPROP 1 LAST CDS_LMAN_SYM_OUTLINE -50,25,50,-25
J 0
(950 2175);
DISPLAY 0.468085 (950 2175);
PAINT GREEN (950 2175);
DISPLAY INVISIBLE (950 2175);
FORCEPROP 2 LAST CDS_LIB w_hdl
J 0
(950 2175);
PAINT MONO (950 2175);
DISPLAY INVISIBLE (950 2175);
FORCEPROP 1 LAST PART_NUMBER 078.22611.0811
J 0
(950 2175);
DISPLAY 0.617021 (950 2175);
PAINT GREEN (950 2175);
DISPLAY INVISIBLE (950 2175);
FORCEPROP 2 LAST SEC_TYPE SMD-BCG5
J 0
(975 2250);
DISPLAY 1.021277 (975 2250);
PAINT ORANGE (975 2250);
DISPLAY INVISIBLE (975 2250);
FORCEPROP 2 LAST SEC 1
J 0
(975 2250);
DISPLAY 0.680851 (975 2250);
PAINT MONO (975 2250);
DISPLAY INVISIBLE (975 2250);
FORCEPROP 1 LAST PACK_TYPE SMD-BCG5
J 0
(950 2175);
DISPLAY 0.617021 (950 2175);
PAINT GREEN (950 2175);
DISPLAY INVISIBLE (950 2175);
FORCEPROP 1 LAST PATH I136
J 0
(950 2175);
DISPLAY 0.617021 (950 2175);
PAINT GREEN (950 2175);
DISPLAY INVISIBLE (950 2175);
FORCEADD GND..1
(950 1950);
FORCEPROP 3 LASTPIN (950 2000) SIG_NAME GND\g
J 0
(960 2010);
DISPLAY 0.659574 (960 2010);
PAINT MONO (960 2010);
DISPLAY INVISIBLE (960 2010);
FORCEPROP 1 LAST PATH I137
J 0
(1025 1950);
DISPLAY 0.872340 (1025 1950);
PAINT AQUA (1025 1950);
DISPLAY INVISIBLE (1025 1950);
FORCEPROP 1 LAST SIZE 1B
J 0
(1025 1900);
DISPLAY 0.872340 (1025 1900);
PAINT GREEN (1025 1900);
DISPLAY INVISIBLE (1025 1900);
FORCEPROP 1 LAST VOLTAGE 0
J 0
(950 1950);
PAINT SKYBLUE (950 1950);
DISPLAY INVISIBLE (950 1950);
FORCEPROP 2 LAST ROOM PVPP_KLM_VR
J 0
(375 2025);
DISPLAY 1.042553 (375 2025);
PAINT GREEN (375 2025);
DISPLAY INVISIBLE (375 2025);
FORCEPROP 2 LAST BOM_COST PVPP_KLM_VR
J 0
(100 2025);
DISPLAY 1.042553 (100 2025);
PAINT WHITE (100 2025);
DISPLAY INVISIBLE (100 2025);
FORCEPROP 2 LAST CDS_LIB mstr_symbols
J 0
(950 1950);
PAINT MONO (950 1950);
DISPLAY INVISIBLE (950 1950);
FORCEPROP 1 LAST BODY_TYPE PLUMBING
J 0
(905 1907);
DISPLAY 0.340426 (905 1907);
PAINT GREEN (905 1907);
DISPLAY INVISIBLE (905 1907);
FORCEPROP 1 LAST HDL_POWER GND
J 0
(950 2100);
DISPLAY 0.872340 (950 2100);
PAINT GREEN (950 2100);
DISPLAY INVISIBLE (950 2100);
FORCEADD SC22U16V5MX-4-GP..1
(650 2175);
FORCEPROP 2 LASTPIN (650 2250) $PN 1
R 1
J 0
(640 2260);
DISPLAY 0.808511 (640 2260);
PAINT ORANGE (640 2260);
FORCEPROP 2 LASTPIN (650 2100) $PN 2
R 1
J 2
(640 2090);
DISPLAY 0.808511 (640 2090);
PAINT ORANGE (640 2090);
FORCEPROP 1 LAST LOCATION C7C7
J 0
(750 2310);
DISPLAY 0.617021 (750 2310);
PAINT GREEN (750 2310);
FORCEPROP 2 LAST ATTRIBUTE 22UF
J 0
(750 2250);
DISPLAY 0.638298 (750 2250);
PAINT GREEN (750 2250);
FORCEPROP 2 LAST TOLERANCE 20%
J 0
(750 2200);
DISPLAY 0.638298 (750 2200);
PAINT GREEN (750 2200);
FORCEPROP 2 LAST RATED 16V
J 0
(750 2150);
DISPLAY 0.638298 (750 2150);
PAINT GREEN (750 2150);
FORCEPROP 2 LAST TYPE X6S
J 0
(750 2100);
DISPLAY 0.638298 (750 2100);
PAINT GREEN (750 2100);
FORCEPROP 2 LAST PACK_SIZE 0805
J 0
(750 2050);
DISPLAY 0.638298 (750 2050);
PAINT GREEN (750 2050);
FORCEPROP 1 LAST VALUE SC22U16V5MX-4-GP
R 1
J 0
(725 1970);
DISPLAY 0.617021 (725 1970);
PAINT GREEN (725 1970);
FORCEPROP 1 LAST PACK_TYPE SMD-BCG5
J 0
(650 2175);
DISPLAY 0.617021 (650 2175);
PAINT GREEN (650 2175);
DISPLAY INVISIBLE (650 2175);
FORCEPROP 2 LAST SEC 1
J 0
(675 2250);
DISPLAY 0.680851 (675 2250);
PAINT MONO (675 2250);
DISPLAY INVISIBLE (675 2250);
FORCEPROP 2 LAST SEC_TYPE SMD-BCG5
J 0
(675 2250);
DISPLAY 1.021277 (675 2250);
PAINT ORANGE (675 2250);
DISPLAY INVISIBLE (675 2250);
FORCEPROP 1 LAST PART_NUMBER 078.22611.0811
J 0
(650 2175);
DISPLAY 0.617021 (650 2175);
PAINT GREEN (650 2175);
DISPLAY INVISIBLE (650 2175);
FORCEPROP 2 LAST CDS_LIB w_hdl
J 0
(650 2175);
PAINT MONO (650 2175);
DISPLAY INVISIBLE (650 2175);
FORCEPROP 1 LAST CDS_LMAN_SYM_OUTLINE -50,25,50,-25
J 0
(650 2175);
DISPLAY 0.468085 (650 2175);
PAINT GREEN (650 2175);
DISPLAY INVISIBLE (650 2175);
FORCEPROP 1 LAST PATH I138
J 0
(650 2175);
DISPLAY 0.617021 (650 2175);
PAINT GREEN (650 2175);
DISPLAY INVISIBLE (650 2175);
FORCEADD GND..1
(650 1950);
FORCEPROP 3 LASTPIN (650 2000) SIG_NAME GND\g
J 0
(660 2010);
DISPLAY 0.659574 (660 2010);
PAINT MONO (660 2010);
DISPLAY INVISIBLE (660 2010);
FORCEPROP 2 LAST CDS_LIB mstr_symbols
J 0
(650 1950);
PAINT MONO (650 1950);
DISPLAY INVISIBLE (650 1950);
FORCEPROP 2 LAST BOM_COST PVPP_KLM_VR
J 0
(-200 2025);
DISPLAY 1.042553 (-200 2025);
PAINT WHITE (-200 2025);
DISPLAY INVISIBLE (-200 2025);
FORCEPROP 2 LAST ROOM PVPP_KLM_VR
J 0
(75 2025);
DISPLAY 1.042553 (75 2025);
PAINT GREEN (75 2025);
DISPLAY INVISIBLE (75 2025);
FORCEPROP 1 LAST VOLTAGE 0
J 0
(650 1950);
PAINT SKYBLUE (650 1950);
DISPLAY INVISIBLE (650 1950);
FORCEPROP 1 LAST SIZE 1B
J 0
(725 1900);
DISPLAY 0.872340 (725 1900);
PAINT GREEN (725 1900);
DISPLAY INVISIBLE (725 1900);
FORCEPROP 1 LAST PATH I139
J 0
(725 1950);
DISPLAY 0.872340 (725 1950);
PAINT AQUA (725 1950);
DISPLAY INVISIBLE (725 1950);
FORCEPROP 1 LAST BODY_TYPE PLUMBING
J 0
(605 1907);
DISPLAY 0.340426 (605 1907);
PAINT GREEN (605 1907);
DISPLAY INVISIBLE (605 1907);
FORCEPROP 1 LAST HDL_POWER GND
J 0
(650 2100);
DISPLAY 0.872340 (650 2100);
PAINT GREEN (650 2100);
DISPLAY INVISIBLE (650 2100);
FORCEADD RES..1
(-1200 4750);
FORCEPROP 1 LAST PACK_TYPE 0402
J 0
(-1125 4650);
DISPLAY 0.617021 (-1125 4650);
PAINT SKYBLUE (-1125 4650);
FORCEPROP 1 LAST TOLERANCE 5%
J 0
(-1250 4650);
DISPLAY 0.617021 (-1250 4650);
PAINT SKYBLUE (-1250 4650);
FORCEPROP 1 LAST PART_NUMBER G21497-005
J 0
(-1325 4700);
DISPLAY 0.617021 (-1325 4700);
PAINT BLUE (-1325 4700);
FORCEPROP 1 LAST VALUE 0.0
J 2
(-1300 4650);
DISPLAY 0.617021 (-1300 4650);
PAINT SKYBLUE (-1300 4650);
FORCEPROP 1 LASTPIN (-1300 4750) $PN 1
J 0
(-1288 4762);
DISPLAY 0.617021 (-1288 4762);
PAINT WHITE (-1288 4762);
FORCEPROP 1 LAST LOCATION R3N7
J 0
(-1300 4800);
DISPLAY 0.617021 (-1300 4800);
PAINT AQUA (-1300 4800);
FORCEPROP 1 LASTPIN (-1100 4750) $PN 2
J 0
(-1138 4762);
DISPLAY 0.617021 (-1138 4762);
PAINT WHITE (-1138 4762);
FORCEPROP 1 LAST MATERIAL CHIP
J 0
(-975 4675);
DISPLAY 0.510638 (-975 4675);
PAINT SKYBLUE (-975 4675);
FORCEPROP 1 LAST WATTAGE 1/16W
J 2
(-900 4775);
DISPLAY 0.510638 (-900 4775);
PAINT SKYBLUE (-900 4775);
FORCEPROP 2 LAST BOM_COST PROC_SIDEBAND
J 0
(-1200 4750);
PAINT MONO (-1200 4750);
DISPLAY INVISIBLE (-1200 4750);
FORCEPROP 2 LAST CDS_LIB mstr_discrete
J 0
(-1200 4750);
DISPLAY 1.340426 (-1200 4750);
PAINT ORANGE (-1200 4750);
DISPLAY INVISIBLE (-1200 4750);
FORCEPROP 2 LAST SEC_TYPE 0402
J 0
(-1250 4975);
DISPLAY 1.021277 (-1250 4975);
PAINT ORANGE (-1250 4975);
DISPLAY INVISIBLE (-1250 4975);
FORCEPROP 2 LAST SEC 1
J 0
(-1250 4975);
DISPLAY 0.680851 (-1250 4975);
PAINT MONO (-1250 4975);
DISPLAY INVISIBLE (-1250 4975);
FORCEPROP 2 LAST ROOM CPU0
J 0
(-1250 4900);
PAINT PEACH (-1250 4900);
DISPLAY INVISIBLE (-1250 4900);
FORCEPROP 0 LAST CDS_SEC 1
J 0
(-900 4800);
PAINT MONO (-900 4800);
DISPLAY INVISIBLE (-900 4800);
FORCEPROP 1 LAST PATH I140
J 0
(-1250 4900);
DISPLAY 0.978723 (-1250 4900);
PAINT WHITE (-1250 4900);
DISPLAY INVISIBLE (-1250 4900);
FORCEPROP 2 LAST CDS_LOCATION R3N7
J 0
(-1675 4750);
DISPLAY 0.617021 (-1675 4750);
PAINT AQUA (-1675 4750);
DISPLAY INVISIBLE (-1675 4750);
FORCEADD IND-150NH-56-GP..1
R 1
(3075 3675);
FORCEPROP 2 LASTPIN (2925 3650) $PN 1
J 2
(2915 3660);
DISPLAY 0.808511 (2915 3660);
PAINT ORANGE (2915 3660);
FORCEPROP 2 LASTPIN (3225 3650) $PN 2
J 0
(3235 3660);
DISPLAY 0.808511 (3235 3660);
PAINT ORANGE (3235 3660);
FORCEPROP 1 LAST VALUE IND-150NH-56-GP
J 0
(2900 3600);
DISPLAY 0.617021 (2900 3600);
PAINT GREEN (2900 3600);
FORCEPROP 2 LAST ATTRIBUTE 150NH
J 0
(2900 3550);
DISPLAY 0.638298 (2900 3550);
PAINT GREEN (2900 3550);
FORCEPROP 2 LAST RATED ISAT=75A@25C
J 0
(2900 3500);
DISPLAY 0.638298 (2900 3500);
PAINT GREEN (2900 3500);
FORCEPROP 2 LAST TYPE IRMS=66A@DELTA_T<40C
J 0
(2900 3450);
DISPLAY 0.638298 (2900 3450);
PAINT GREEN (2900 3450);
FORCEPROP 2 LAST PACK_SIZE DCR=0.17MOHM
J 0
(2900 3400);
DISPLAY 0.638298 (2900 3400);
PAINT GREEN (2900 3400);
FORCEPROP 1 LAST LOCATION L7C2
J 0
(2920 3720);
DISPLAY 0.617021 (2920 3720);
PAINT GREEN (2920 3720);
FORCEPROP 1 LAST PART_NUMBER 068.1512N.M001
R 1
J 0
(3075 3675);
DISPLAY 0.617021 (3075 3675);
PAINT GREEN (3075 3675);
DISPLAY INVISIBLE (3075 3675);
FORCEPROP 2 LAST CDS_LIB w_hdl
R 1
J 0
(3075 3675);
PAINT MONO (3075 3675);
DISPLAY INVISIBLE (3075 3675);
FORCEPROP 1 LAST CDS_LMAN_SYM_OUTLINE -75,100,75,-100
R 1
J 0
(3075 3675);
DISPLAY 0.468085 (3075 3675);
PAINT GREEN (3075 3675);
DISPLAY INVISIBLE (3075 3675);
FORCEPROP 2 LAST SEC_TYPE DISCRET-GA1
J 0
(3225 3750);
DISPLAY 1.021277 (3225 3750);
PAINT ORANGE (3225 3750);
DISPLAY INVISIBLE (3225 3750);
FORCEPROP 2 LAST SEC 1
J 0
(3225 3750);
DISPLAY 0.680851 (3225 3750);
PAINT MONO (3225 3750);
DISPLAY INVISIBLE (3225 3750);
FORCEPROP 1 LAST PACK_TYPE DISCRET-GA1
R 1
J 0
(3075 3675);
DISPLAY 0.617021 (3075 3675);
PAINT GREEN (3075 3675);
DISPLAY INVISIBLE (3075 3675);
FORCEPROP 1 LAST PATH I141
R 1
J 0
(3075 3675);
DISPLAY 0.617021 (3075 3675);
PAINT GREEN (3075 3675);
DISPLAY INVISIBLE (3075 3675);
FORCEADD IND-100NH-35-GP..1
R 1
(225 2475);
FORCEPROP 2 LASTPIN (75 2450) $PN 1
J 2
(65 2460);
DISPLAY 0.808511 (65 2460);
PAINT ORANGE (65 2460);
FORCEPROP 2 LASTPIN (375 2450) $PN 2
J 0
(385 2460);
DISPLAY 0.808511 (385 2460);
PAINT ORANGE (385 2460);
FORCEPROP 2 LAST RATED ISAT=16A@25C
J 0
(75 2300);
DISPLAY 0.638298 (75 2300);
PAINT GREEN (75 2300);
FORCEPROP 2 LAST PACK_SIZE DCR=0.16MOHM
J 0
(75 2200);
DISPLAY 0.638298 (75 2200);
PAINT GREEN (75 2200);
FORCEPROP 2 LAST TYPE IRMS=29A@DELTA_T<45C
J 0
(75 2250);
DISPLAY 0.638298 (75 2250);
PAINT GREEN (75 2250);
FORCEPROP 1 LAST LOCATION L7C1
J 0
(100 2525);
DISPLAY 0.617021 (100 2525);
PAINT GREEN (100 2525);
FORCEPROP 2 LAST ATTRIBUTE 100NH
J 0
(75 2350);
DISPLAY 0.638298 (75 2350);
PAINT GREEN (75 2350);
FORCEPROP 1 LAST VALUE IND-100NH-35-GP
J 0
(75 2400);
DISPLAY 0.617021 (75 2400);
PAINT GREEN (75 2400);
FORCEPROP 1 LAST CDS_LMAN_SYM_OUTLINE -75,100,75,-100
R 1
J 0
(225 2475);
DISPLAY 0.468085 (225 2475);
PAINT GREEN (225 2475);
DISPLAY INVISIBLE (225 2475);
FORCEPROP 2 LAST CDS_LIB w_hdl
R 1
J 0
(225 2475);
PAINT MONO (225 2475);
DISPLAY INVISIBLE (225 2475);
FORCEPROP 1 LAST PART_NUMBER 068.1011N.M001
R 1
J 0
(225 2475);
DISPLAY 0.617021 (225 2475);
PAINT GREEN (225 2475);
DISPLAY INVISIBLE (225 2475);
FORCEPROP 2 LAST SEC_TYPE DISCRET-G8
J 0
(75 2450);
DISPLAY 1.021277 (75 2450);
PAINT ORANGE (75 2450);
DISPLAY INVISIBLE (75 2450);
FORCEPROP 2 LAST SEC 1
J 0
(75 2450);
DISPLAY 0.680851 (75 2450);
PAINT MONO (75 2450);
DISPLAY INVISIBLE (75 2450);
FORCEPROP 1 LAST PACK_TYPE DISCRET-G8
R 1
J 0
(225 2475);
DISPLAY 0.617021 (225 2475);
PAINT GREEN (225 2475);
DISPLAY INVISIBLE (225 2475);
FORCEPROP 1 LAST PATH I142
R 1
J 0
(225 2475);
DISPLAY 0.617021 (225 2475);
PAINT GREEN (225 2475);
DISPLAY INVISIBLE (225 2475);
FORCEADD SC1U10V2KX-4-GP..1
(-825 4200);
FORCEPROP 2 LASTPIN (-825 4275) $PN 1
R 1
J 0
(-835 4285);
DISPLAY 0.808511 (-835 4285);
PAINT ORANGE (-835 4285);
FORCEPROP 2 LASTPIN (-825 4125) $PN 2
R 1
J 2
(-835 4115);
DISPLAY 0.808511 (-835 4115);
PAINT ORANGE (-835 4115);
FORCEPROP 1 LAST LOCATION C7C20
J 0
(-700 4280);
DISPLAY 0.617021 (-700 4280);
PAINT GREEN (-700 4280);
FORCEPROP 2 LAST ATTRIBUTE 1UF
J 0
(-700 4225);
DISPLAY 0.638298 (-700 4225);
PAINT GREEN (-700 4225);
FORCEPROP 2 LAST TOLERANCE 10%
J 0
(-700 4175);
DISPLAY 0.638298 (-700 4175);
PAINT GREEN (-700 4175);
FORCEPROP 2 LAST RATED 10V
J 0
(-700 4125);
DISPLAY 0.638298 (-700 4125);
PAINT GREEN (-700 4125);
FORCEPROP 2 LAST PACK_SIZE 0402
J 0
(-700 4075);
DISPLAY 0.638298 (-700 4075);
PAINT GREEN (-700 4075);
FORCEPROP 1 LAST VALUE SC1U10V2KX-4-GP
R 1
J 0
(-725 3975);
DISPLAY 0.617021 (-725 3975);
PAINT GREEN (-725 3975);
FORCEPROP 1 LAST CDS_LMAN_SYM_OUTLINE -50,25,50,-25
J 0
(-825 4200);
DISPLAY 0.468085 (-825 4200);
PAINT GREEN (-825 4200);
DISPLAY INVISIBLE (-825 4200);
FORCEPROP 1 LAST PATH I143
J 0
(-825 4200);
DISPLAY 0.617021 (-825 4200);
PAINT GREEN (-825 4200);
DISPLAY INVISIBLE (-825 4200);
FORCEPROP 2 LAST CDS_LIB w_hdl
J 0
(-825 4200);
PAINT MONO (-825 4200);
DISPLAY INVISIBLE (-825 4200);
FORCEPROP 1 LAST PART_NUMBER 78.10523.8FL
J 0
(-825 4200);
DISPLAY 0.617021 (-825 4200);
PAINT GREEN (-825 4200);
DISPLAY INVISIBLE (-825 4200);
FORCEPROP 2 LAST SEC_TYPE SMD-BCG6
J 0
(-800 4275);
DISPLAY 1.021277 (-800 4275);
PAINT ORANGE (-800 4275);
DISPLAY INVISIBLE (-800 4275);
FORCEPROP 2 LAST SEC 1
J 0
(-800 4275);
DISPLAY 0.680851 (-800 4275);
PAINT MONO (-800 4275);
DISPLAY INVISIBLE (-800 4275);
FORCEPROP 1 LAST PACK_TYPE SMD-BCG6
J 0
(-825 4200);
DISPLAY 0.617021 (-825 4200);
PAINT GREEN (-825 4200);
DISPLAY INVISIBLE (-825 4200);
FORCEADD 1R3F-GP..1
(2625 3100);
FORCEPROP 2 LAST PACK_SIZE 0603
J 0
(2675 2975);
DISPLAY 0.638298 (2675 2975);
PAINT GREEN (2675 2975);
FORCEPROP 2 LASTPIN (2625 3225) $PN 1
R 1
J 0
(2615 3235);
DISPLAY 0.808511 (2615 3235);
PAINT ORANGE (2615 3235);
FORCEPROP 1 LAST LOCATION RT48
J 0
(2675 3225);
DISPLAY 0.617021 (2675 3225);
PAINT GREEN (2675 3225);
FORCEPROP 2 LASTPIN (2625 2975) $PN 2
R 1
J 2
(2615 2965);
DISPLAY 0.808511 (2615 2965);
PAINT ORANGE (2615 2965);
FORCEPROP 0 LAST POP NOPOP
J 0
(2675 2925);
DISPLAY 0.638298 (2675 2925);
PAINT RED (2675 2925);
FORCEPROP 1 LAST VALUE 1R3F-GP
J 0
(2675 3175);
DISPLAY 0.617021 (2675 3175);
PAINT GREEN (2675 3175);
FORCEPROP 2 LAST RATED 1/10W
J 0
(2675 3025);
DISPLAY 0.638298 (2675 3025);
PAINT GREEN (2675 3025);
FORCEPROP 2 LAST TOLERANCE 1%
J 0
(2675 3075);
DISPLAY 0.638298 (2675 3075);
PAINT GREEN (2675 3075);
FORCEPROP 2 LAST ATTRIBUTE 1 OHM
J 0
(2675 3125);
DISPLAY 0.638298 (2675 3125);
PAINT GREEN (2675 3125);
FORCEPROP 1 LAST PACK_TYPE RCL_GP
J 0
(2625 3100);
DISPLAY 0.617021 (2625 3100);
PAINT GREEN (2625 3100);
DISPLAY INVISIBLE (2625 3100);
FORCEPROP 2 LAST SEC 1
J 0
(2675 3200);
DISPLAY 0.680851 (2675 3200);
PAINT MONO (2675 3200);
DISPLAY INVISIBLE (2675 3200);
FORCEPROP 2 LAST SEC_TYPE RCL_GP
J 0
(2675 3200);
DISPLAY 1.021277 (2675 3200);
PAINT ORANGE (2675 3200);
DISPLAY INVISIBLE (2675 3200);
FORCEPROP 1 LAST PART_NUMBER 64.1R005.55L
J 0
(2625 3100);
DISPLAY 0.617021 (2625 3100);
PAINT GREEN (2625 3100);
DISPLAY INVISIBLE (2625 3100);
FORCEPROP 2 LAST CDS_LIB w_hdl
J 0
(2625 3100);
DISPLAY INVISIBLE (2625 3100);
FORCEPROP 1 LAST CDS_LMAN_SYM_OUTLINE -50,75,50,-75
J 0
(2625 3100);
DISPLAY 0.468085 (2625 3100);
PAINT GREEN (2625 3100);
DISPLAY INVISIBLE (2625 3100);
FORCEPROP 1 LAST PATH I144
J 0
(2625 3100);
DISPLAY 0.617021 (2625 3100);
PAINT GREEN (2625 3100);
DISPLAY INVISIBLE (2625 3100);
FORCEADD CAPP..1
R 2
(1400 1300);
FORCEPROP 1 LAST LOCATION C3N26
J 0
(1450 1425);
DISPLAY 0.617021 (1450 1425);
PAINT AQUA (1450 1425);
FORCEPROP 1 LAST PACK_TYPE 3018
J 0
(1450 1125);
DISPLAY 0.617021 (1450 1125);
PAINT SKYBLUE (1450 1125);
FORCEPROP 1 LAST VALUE 470UF
J 0
(1450 1375);
DISPLAY 0.617021 (1450 1375);
PAINT SKYBLUE (1450 1375);
FORCEPROP 1 LAST VOLTAGE 2.5V
J 0
(1450 1275);
DISPLAY 0.617021 (1450 1275);
PAINT SKYBLUE (1450 1275);
FORCEPROP 1 LAST MATERIAL ALUM
J 0
(1450 1225);
DISPLAY 0.617021 (1450 1225);
PAINT SKYBLUE (1450 1225);
FORCEPROP 1 LASTPIN (1400 1200) $PN 2
J 2
(1390 1185);
DISPLAY 0.617021 (1390 1185);
PAINT WHITE (1390 1185);
FORCEPROP 0 LAST GROUP PWR_BULK_CAP
J 0
(1455 1075);
DISPLAY 0.638298 (1455 1075);
PAINT BROWN (1455 1075);
DISPLAY BOTH (1455 1075);
FORCEPROP 1 LASTPIN (1400 1400) $PN 1
J 2
(1390 1385);
DISPLAY 0.617021 (1390 1385);
PAINT WHITE (1390 1385);
FORCEPROP 1 LAST TOLERANCE 20%
J 0
(1450 1325);
DISPLAY 0.617021 (1450 1325);
PAINT SKYBLUE (1450 1325);
FORCEPROP 1 LAST PART_NUMBER 699013-049
J 0
(1450 1175);
DISPLAY 0.617021 (1450 1175);
PAINT BLUE (1450 1175);
FORCEPROP 1 LAST PATH I145
J 2
(1350 1450);
DISPLAY 0.978723 (1350 1450);
PAINT ORANGE (1350 1450);
DISPLAY INVISIBLE (1350 1450);
FORCEPROP 2 LAST $SEC 1
J 0
(2060 1940);
DISPLAY 0.680851 (2060 1940);
PAINT MONO (2060 1940);
DISPLAY INVISIBLE (2060 1940);
FORCEPROP 2 LAST CDS_SEC 1
J 0
(1350 1500);
PAINT MONO (1350 1500);
DISPLAY INVISIBLE (1350 1500);
FORCEPROP 2 LAST BOM_COST PROC_VRD_PVCCIO_CPU0
J 2
(1350 1450);
PAINT MONO (1350 1450);
DISPLAY INVISIBLE (1350 1450);
FORCEPROP 2 LAST CDS_LIB mstr_discrete
J 0
(1400 1300);
PAINT ORANGE (1400 1300);
DISPLAY INVISIBLE (1400 1300);
FORCEPROP 2 LAST ROOM PVCCIO_CPU0
J 0
(1350 1425);
PAINT MONO (1350 1425);
DISPLAY INVISIBLE (1350 1425);
FORCEPROP 2 LAST CDS_LOCATION C3N26
J 2
(1350 1400);
DISPLAY 0.617021 (1350 1400);
PAINT AQUA (1350 1400);
DISPLAY INVISIBLE (1350 1400);
FORCEADD CAPP..1
R 2
(1950 1300);
FORCEPROP 1 LASTPIN (1950 1200) $PN 2
J 2
(1940 1185);
DISPLAY 0.617021 (1940 1185);
PAINT WHITE (1940 1185);
FORCEPROP 1 LASTPIN (1950 1400) $PN 1
J 2
(1940 1385);
DISPLAY 0.617021 (1940 1385);
PAINT WHITE (1940 1385);
FORCEPROP 1 LAST MATERIAL ALUM
J 0
(2000 1225);
DISPLAY 0.617021 (2000 1225);
PAINT SKYBLUE (2000 1225);
FORCEPROP 1 LAST VOLTAGE 2.5V
J 0
(2000 1275);
DISPLAY 0.617021 (2000 1275);
PAINT SKYBLUE (2000 1275);
FORCEPROP 1 LAST TOLERANCE 20%
J 0
(2000 1325);
DISPLAY 0.617021 (2000 1325);
PAINT SKYBLUE (2000 1325);
FORCEPROP 1 LAST VALUE 470UF
J 0
(2000 1375);
DISPLAY 0.617021 (2000 1375);
PAINT SKYBLUE (2000 1375);
FORCEPROP 1 LAST PACK_TYPE 3018
J 0
(2000 1125);
DISPLAY 0.617021 (2000 1125);
PAINT SKYBLUE (2000 1125);
FORCEPROP 1 LAST LOCATION C3N38
J 0
(2000 1425);
DISPLAY 0.617021 (2000 1425);
PAINT AQUA (2000 1425);
FORCEPROP 0 LAST GROUP PWR_BULK_CAP
J 0
(2005 1075);
DISPLAY 0.638298 (2005 1075);
PAINT BROWN (2005 1075);
DISPLAY BOTH (2005 1075);
FORCEPROP 1 LAST PART_NUMBER 699013-049
J 0
(2000 1175);
DISPLAY 0.617021 (2000 1175);
PAINT BLUE (2000 1175);
FORCEPROP 2 LAST ROOM PVCCIO_CPU0
J 0
(1900 1425);
PAINT MONO (1900 1425);
DISPLAY INVISIBLE (1900 1425);
FORCEPROP 2 LAST CDS_LIB mstr_discrete
J 0
(1950 1300);
PAINT ORANGE (1950 1300);
DISPLAY INVISIBLE (1950 1300);
FORCEPROP 2 LAST BOM_COST PROC_VRD_PVCCIO_CPU0
J 2
(1900 1450);
PAINT MONO (1900 1450);
DISPLAY INVISIBLE (1900 1450);
FORCEPROP 2 LAST CDS_SEC 1
J 0
(1900 1500);
PAINT MONO (1900 1500);
DISPLAY INVISIBLE (1900 1500);
FORCEPROP 2 LAST $SEC 1
J 0
(2610 1940);
DISPLAY 0.680851 (2610 1940);
PAINT MONO (2610 1940);
DISPLAY INVISIBLE (2610 1940);
FORCEPROP 1 LAST PATH I146
J 2
(1900 1450);
DISPLAY 0.978723 (1900 1450);
PAINT ORANGE (1900 1450);
DISPLAY INVISIBLE (1900 1450);
FORCEPROP 2 LAST CDS_LOCATION C3N38
J 2
(1900 1400);
DISPLAY 0.617021 (1900 1400);
PAINT AQUA (1900 1400);
DISPLAY INVISIBLE (1900 1400);
FORCEADD CAPP..1
R 2
(850 1300);
FORCEPROP 1 LAST PART_NUMBER 699013-049
J 0
(900 1175);
DISPLAY 0.617021 (900 1175);
PAINT BLUE (900 1175);
FORCEPROP 1 LAST PACK_TYPE 3018
J 0
(900 1125);
DISPLAY 0.617021 (900 1125);
PAINT SKYBLUE (900 1125);
FORCEPROP 1 LAST LOCATION C3N35
J 0
(900 1425);
DISPLAY 0.617021 (900 1425);
PAINT AQUA (900 1425);
FORCEPROP 1 LAST VALUE 470UF
J 0
(900 1375);
DISPLAY 0.617021 (900 1375);
PAINT SKYBLUE (900 1375);
FORCEPROP 1 LAST TOLERANCE 20%
J 0
(900 1325);
DISPLAY 0.617021 (900 1325);
PAINT SKYBLUE (900 1325);
FORCEPROP 1 LAST VOLTAGE 2.5V
J 0
(900 1275);
DISPLAY 0.617021 (900 1275);
PAINT SKYBLUE (900 1275);
FORCEPROP 1 LAST MATERIAL ALUM
J 0
(900 1225);
DISPLAY 0.617021 (900 1225);
PAINT SKYBLUE (900 1225);
FORCEPROP 1 LASTPIN (850 1400) $PN 1
J 2
(840 1385);
DISPLAY 0.617021 (840 1385);
PAINT WHITE (840 1385);
FORCEPROP 1 LASTPIN (850 1200) $PN 2
J 2
(840 1185);
DISPLAY 0.617021 (840 1185);
PAINT WHITE (840 1185);
FORCEPROP 0 LAST GROUP PWR_BULK_CAP
J 0
(905 1075);
DISPLAY 0.638298 (905 1075);
PAINT BROWN (905 1075);
DISPLAY BOTH (905 1075);
FORCEPROP 2 LAST $SEC 1
J 0
(1510 1940);
DISPLAY 0.680851 (1510 1940);
PAINT MONO (1510 1940);
DISPLAY INVISIBLE (1510 1940);
FORCEPROP 2 LAST CDS_SEC 1
J 0
(800 1500);
PAINT MONO (800 1500);
DISPLAY INVISIBLE (800 1500);
FORCEPROP 2 LAST BOM_COST PROC_VRD_PVCCIO_CPU0
J 2
(800 1450);
PAINT MONO (800 1450);
DISPLAY INVISIBLE (800 1450);
FORCEPROP 2 LAST CDS_LOCATION C3N35
J 2
(800 1400);
DISPLAY 0.617021 (800 1400);
PAINT AQUA (800 1400);
DISPLAY INVISIBLE (800 1400);
FORCEPROP 2 LAST CDS_LIB mstr_discrete
J 0
(850 1300);
PAINT ORANGE (850 1300);
DISPLAY INVISIBLE (850 1300);
FORCEPROP 1 LAST PATH I18
J 0
(800 1450);
DISPLAY 0.978723 (800 1450);
PAINT ORANGE (800 1450);
DISPLAY INVISIBLE (800 1450);
FORCEPROP 2 LAST ROOM PVCCIO_CPU0
J 0
(800 1425);
PAINT MONO (800 1425);
DISPLAY INVISIBLE (800 1425);
FORCEADD OFFPAGE..2
(3150 4825);
FORCEPROP 2 LAST $XR0 211 
J 0
(3339 4825);
DISPLAY 0.638298 (3339 4825);
PAINT MONO (3339 4825);
FORCEPROP 2 LAST ROOM PVCCIO_CPU0
J 0
(2750 4900);
DISPLAY 3.127660 (2750 4900);
PAINT WHITE (2750 4900);
DISPLAY INVISIBLE (2750 4900);
FORCEPROP 2 LAST CDS_LIB mstr_standard
J 0
(3150 4825);
DISPLAY 1.617021 (3150 4825);
PAINT ORANGE (3150 4825);
DISPLAY INVISIBLE (3150 4825);
FORCEPROP 2 LAST BOM_COST PROC_VRD_PVCCIO_CPU0
J 0
(3350 4875);
DISPLAY 2.340426 (3350 4875);
PAINT WHITE (3350 4875);
DISPLAY INVISIBLE (3350 4875);
FORCEPROP 2 LAST PATH I19
J 0
(3600 4875);
DISPLAY 1.021277 (3600 4875);
PAINT ORANGE (3600 4875);
DISPLAY INVISIBLE (3600 4875);
FORCEPROP 1 LAST OFFPAGE TRUE
J 0
(3475 4700);
PAINT GREEN (3475 4700);
DISPLAY INVISIBLE (3475 4700);
FORCEPROP 1 LAST COMMENT_BODY TRUE
J 0
(3105 4730);
DISPLAY 2.787234 (3105 4730);
PAINT PEACH (3105 4730);
DISPLAY INVISIBLE (3105 4730);
FORCEADD OFFPAGE..2
(3050 4500);
FORCEPROP 2 LAST $XR0 211 
J 0
(3239 4500);
DISPLAY 0.638298 (3239 4500);
PAINT MONO (3239 4500);
FORCEPROP 2 LAST ROOM PVCCIO_CPU0
J 0
(2650 4575);
DISPLAY 3.127660 (2650 4575);
PAINT WHITE (2650 4575);
DISPLAY INVISIBLE (2650 4575);
FORCEPROP 2 LAST CDS_LIB mstr_standard
J 0
(3050 4500);
DISPLAY 1.617021 (3050 4500);
PAINT ORANGE (3050 4500);
DISPLAY INVISIBLE (3050 4500);
FORCEPROP 2 LAST PATH I20
J 0
(3225 4575);
DISPLAY 1.021277 (3225 4575);
PAINT ORANGE (3225 4575);
DISPLAY INVISIBLE (3225 4575);
FORCEPROP 2 LAST BOM_COST PROC_VRD_PVCCIO_CPU0
J 0
(3250 4550);
DISPLAY 2.340426 (3250 4550);
PAINT WHITE (3250 4550);
DISPLAY INVISIBLE (3250 4550);
FORCEPROP 1 LAST OFFPAGE TRUE
J 0
(3375 4375);
PAINT GREEN (3375 4375);
DISPLAY INVISIBLE (3375 4375);
FORCEPROP 1 LAST COMMENT_BODY TRUE
J 0
(3005 4405);
DISPLAY 2.787234 (3005 4405);
PAINT PEACH (3005 4405);
DISPLAY INVISIBLE (3005 4405);
FORCEADD OFFPAGE..2
(2875 4150);
FORCEPROP 2 LAST $XR0 211 
J 0
(3064 4150);
DISPLAY 0.638298 (3064 4150);
PAINT MONO (3064 4150);
FORCEPROP 2 LAST BOM_COST PROC_VRD_PVCCIO_CPU0
J 0
(3075 4200);
DISPLAY 2.340426 (3075 4200);
PAINT WHITE (3075 4200);
DISPLAY INVISIBLE (3075 4200);
FORCEPROP 2 LAST PATH I21
J 0
(3200 4200);
DISPLAY 1.021277 (3200 4200);
PAINT ORANGE (3200 4200);
DISPLAY INVISIBLE (3200 4200);
FORCEPROP 2 LAST ROOM PVCCIO_CPU0
J 0
(2475 4225);
DISPLAY 3.127660 (2475 4225);
PAINT WHITE (2475 4225);
DISPLAY INVISIBLE (2475 4225);
FORCEPROP 2 LAST CDS_LIB mstr_standard
J 0
(2875 4150);
DISPLAY 1.617021 (2875 4150);
PAINT ORANGE (2875 4150);
DISPLAY INVISIBLE (2875 4150);
FORCEPROP 1 LAST OFFPAGE TRUE
J 0
(3200 4025);
PAINT GREEN (3200 4025);
DISPLAY INVISIBLE (3200 4025);
FORCEPROP 1 LAST COMMENT_BODY TRUE
J 0
(2830 4055);
DISPLAY 2.787234 (2830 4055);
PAINT PEACH (2830 4055);
DISPLAY INVISIBLE (2830 4055);
FORCEADD PVCCIO_CPU0..1
(4025 3775);
FORCEPROP 3 LASTPIN (4025 3725) SIG_NAME PVCCIO_CPU0\g
J 0
(4035 3735);
DISPLAY 0.659574 (4035 3735);
PAINT MONO (4035 3735);
DISPLAY INVISIBLE (4035 3735);
FORCEPROP 1 LAST VOLTAGE 1.1V
J 0
(3980 3732);
DISPLAY 0.340426 (3980 3732);
PAINT SKYBLUE (3980 3732);
DISPLAY INVISIBLE (3980 3732);
FORCEPROP 2 LAST CDS_LIB mstr_symbols
J 0
(4025 3775);
PAINT ORANGE (4025 3775);
DISPLAY INVISIBLE (4025 3775);
FORCEPROP 1 LAST PATH I22
J 0
(4075 3800);
DISPLAY 0.872340 (4075 3800);
PAINT AQUA (4075 3800);
DISPLAY INVISIBLE (4075 3800);
FORCEPROP 1 LAST BODY_TYPE PLUMBING
J 0
(3980 3732);
DISPLAY 0.340426 (3980 3732);
PAINT GREEN (3980 3732);
DISPLAY INVISIBLE (3980 3732);
FORCEPROP 1 LAST HDL_POWER PVCCIO_CPU0
J 1
(4025 3825);
DISPLAY 0.872340 (4025 3825);
PAINT GREEN (4025 3825);
DISPLAY INVISIBLE (4025 3825);
FORCEADD CAP_A..1
(3350 3450);
FORCEPROP 1 LAST TOLERANCE 20%
J 0
(3400 3400);
DISPLAY 0.617021 (3400 3400);
PAINT SKYBLUE (3400 3400);
FORCEPROP 1 LAST MATERIAL X6S
J 0
(3400 3350);
DISPLAY 0.617021 (3400 3350);
PAINT SKYBLUE (3400 3350);
FORCEPROP 1 LASTPIN (3350 3350) $PN 2
J 0
(3360 3330);
DISPLAY 0.617021 (3360 3330);
PAINT WHITE (3360 3330);
FORCEPROP 1 LAST VOLTAGE 4V
J 0
(3400 3450);
DISPLAY 0.617021 (3400 3450);
PAINT SKYBLUE (3400 3450);
FORCEPROP 1 LASTPIN (3350 3550) $PN 1
J 0
(3360 3530);
DISPLAY 0.617021 (3360 3530);
PAINT WHITE (3360 3530);
FORCEPROP 1 LAST LOCATION C7C6
J 0
(3400 3550);
DISPLAY 0.617021 (3400 3550);
PAINT AQUA (3400 3550);
FORCEPROP 1 LAST VALUE 22.0UF
J 0
(3400 3500);
DISPLAY 0.617021 (3400 3500);
PAINT SKYBLUE (3400 3500);
FORCEPROP 1 LAST PART_NUMBER E15431-004
J 0
(3400 3300);
DISPLAY 0.617021 (3400 3300);
PAINT BLUE (3400 3300);
FORCEPROP 1 LAST PACK_TYPE 0603V
J 0
(3400 3250);
DISPLAY 0.617021 (3400 3250);
PAINT SKYBLUE (3400 3250);
FORCEPROP 0 LAST GROUP PWR_MLCC_CAP
J 0
(3406 3187);
DISPLAY 0.638298 (3406 3187);
PAINT BROWN (3406 3187);
DISPLAY BOTH (3406 3187);
FORCEPROP 2 LAST CDS_LIB dev_discrete
J 0
(3350 3450);
PAINT ORANGE (3350 3450);
DISPLAY INVISIBLE (3350 3450);
FORCEPROP 2 LAST ROOM PVCCIO_CPU0
J 0
(3400 3600);
DISPLAY 2.340426 (3400 3600);
PAINT WHITE (3400 3600);
DISPLAY INVISIBLE (3400 3600);
FORCEPROP 1 LAST PATH I23
J 0
(3400 3600);
DISPLAY 0.978723 (3400 3600);
PAINT WHITE (3400 3600);
DISPLAY INVISIBLE (3400 3600);
FORCEPROP 2 LAST SEC 1
J 0
(3405 3650);
DISPLAY 1.106383 (3405 3650);
PAINT MONO (3405 3650);
DISPLAY INVISIBLE (3405 3650);
FORCEPROP 2 LAST SEC_TYPE 0603V
J 0
(3405 3650);
DISPLAY 1.659574 (3405 3650);
PAINT ORANGE (3405 3650);
DISPLAY INVISIBLE (3405 3650);
FORCEPROP 2 LAST CDS_SEC 1
J 0
(3400 3600);
PAINT ORANGE (3400 3600);
DISPLAY INVISIBLE (3400 3600);
FORCEPROP 2 LAST BOM_COST PROC_VRD_PVCCIO_CPU0
J 0
(3400 3600);
DISPLAY 2.340426 (3400 3600);
PAINT WHITE (3400 3600);
DISPLAY INVISIBLE (3400 3600);
FORCEPROP 2 LAST CDS_LOCATION C7C6
J 0
(3400 3550);
DISPLAY 0.617021 (3400 3550);
PAINT AQUA (3400 3550);
DISPLAY INVISIBLE (3400 3550);
FORCEADD GND..1
(4025 3025);
FORCEPROP 3 LASTPIN (4025 3075) SIG_NAME GND\g
J 0
(4035 3085);
DISPLAY 0.659574 (4035 3085);
PAINT MONO (4035 3085);
DISPLAY INVISIBLE (4035 3085);
FORCEPROP 1 LAST VOLTAGE 0.0V
J 0
(3980 2982);
DISPLAY 0.340426 (3980 2982);
PAINT SKYBLUE (3980 2982);
DISPLAY INVISIBLE (3980 2982);
FORCEPROP 2 LAST CDS_LIB mstr_symbols
J 0
(4025 3025);
DISPLAY 1.617021 (4025 3025);
PAINT ORANGE (4025 3025);
DISPLAY INVISIBLE (4025 3025);
FORCEPROP 1 LAST PATH I24
J 0
(4100 3025);
DISPLAY 0.872340 (4100 3025);
PAINT AQUA (4100 3025);
DISPLAY INVISIBLE (4100 3025);
FORCEPROP 1 LAST SIZE 1B
J 0
(4100 2975);
DISPLAY 2.787234 (4100 2975);
PAINT GREEN (4100 2975);
DISPLAY INVISIBLE (4100 2975);
FORCEPROP 2 LAST BOM_COST PROC_VRD_PVCCIO_CPU0
J 0
(3650 3100);
DISPLAY 2.340426 (3650 3100);
PAINT WHITE (3650 3100);
DISPLAY INVISIBLE (3650 3100);
FORCEPROP 2 LAST ROOM PVCCIO_CPU0
J 0
(3475 3100);
DISPLAY 3.127660 (3475 3100);
PAINT WHITE (3475 3100);
DISPLAY INVISIBLE (3475 3100);
FORCEPROP 1 LAST BODY_TYPE PLUMBING
J 0
(3980 2982);
DISPLAY 0.340426 (3980 2982);
PAINT GREEN (3980 2982);
DISPLAY INVISIBLE (3980 2982);
FORCEPROP 1 LAST HDL_POWER GND
J 0
(4025 3175);
DISPLAY 2.787234 (4025 3175);
PAINT GREEN (4025 3175);
DISPLAY INVISIBLE (4025 3175);
FORCEADD GND..1
(1900 3200);
FORCEPROP 3 LASTPIN (1900 3250) SIG_NAME GND\g
J 0
(1910 3260);
DISPLAY 0.659574 (1910 3260);
PAINT MONO (1910 3260);
DISPLAY INVISIBLE (1910 3260);
FORCEPROP 2 LAST ROOM PVCCIO_CPU0
J 0
(1350 3275);
DISPLAY 3.127660 (1350 3275);
PAINT WHITE (1350 3275);
DISPLAY INVISIBLE (1350 3275);
FORCEPROP 1 LAST VOLTAGE 0.0V
J 0
(1855 3157);
DISPLAY 0.340426 (1855 3157);
PAINT SKYBLUE (1855 3157);
DISPLAY INVISIBLE (1855 3157);
FORCEPROP 1 LAST PATH I29
J 0
(1975 3200);
DISPLAY 0.872340 (1975 3200);
PAINT AQUA (1975 3200);
DISPLAY INVISIBLE (1975 3200);
FORCEPROP 1 LAST SIZE 1B
J 0
(1975 3150);
DISPLAY 2.787234 (1975 3150);
PAINT GREEN (1975 3150);
DISPLAY INVISIBLE (1975 3150);
FORCEPROP 2 LAST CDS_LIB mstr_symbols
J 0
(1900 3200);
DISPLAY 1.617021 (1900 3200);
PAINT ORANGE (1900 3200);
DISPLAY INVISIBLE (1900 3200);
FORCEPROP 2 LAST BOM_COST PROC_VRD_PVCCIO_CPU0
J 0
(1525 3275);
DISPLAY 2.340426 (1525 3275);
PAINT WHITE (1525 3275);
DISPLAY INVISIBLE (1525 3275);
FORCEPROP 1 LAST BODY_TYPE PLUMBING
J 0
(1855 3157);
DISPLAY 0.340426 (1855 3157);
PAINT GREEN (1855 3157);
DISPLAY INVISIBLE (1855 3157);
FORCEPROP 1 LAST HDL_POWER GND
J 0
(1900 3350);
DISPLAY 2.787234 (1900 3350);
PAINT GREEN (1900 3350);
DISPLAY INVISIBLE (1900 3350);
FORCEADD CAP..1
(-350 4225);
FORCEPROP 1 LASTPIN (-350 4125) $PN 2
J 0
(-340 4105);
DISPLAY 0.617021 (-340 4105);
PAINT WHITE (-340 4105);
FORCEPROP 1 LAST VOLTAGE 16V
J 0
(-300 4225);
DISPLAY 0.617021 (-300 4225);
PAINT SKYBLUE (-300 4225);
FORCEPROP 1 LAST TOLERANCE 10%
J 0
(-300 4175);
DISPLAY 0.617021 (-300 4175);
PAINT SKYBLUE (-300 4175);
FORCEPROP 1 LASTPIN (-350 4325) $PN 1
J 0
(-340 4305);
DISPLAY 0.617021 (-340 4305);
PAINT WHITE (-340 4305);
FORCEPROP 1 LAST LOCATION C7C18
J 0
(-300 4325);
DISPLAY 0.617021 (-300 4325);
PAINT AQUA (-300 4325);
FORCEPROP 1 LAST PACK_TYPE 0402
J 0
(-300 4025);
DISPLAY 0.617021 (-300 4025);
PAINT SKYBLUE (-300 4025);
FORCEPROP 1 LAST PART_NUMBER A36096-155
J 0
(-300 4075);
DISPLAY 0.617021 (-300 4075);
PAINT BLUE (-300 4075);
FORCEPROP 1 LAST MATERIAL X7R
J 0
(-300 4125);
DISPLAY 0.617021 (-300 4125);
PAINT SKYBLUE (-300 4125);
FORCEPROP 1 LAST VALUE 0.22UF
J 0
(-300 4275);
DISPLAY 0.617021 (-300 4275);
PAINT SKYBLUE (-300 4275);
FORCEPROP 2 LAST SEC_TYPE 0402
J 0
(-300 4425);
DISPLAY 1.659574 (-300 4425);
PAINT ORANGE (-300 4425);
DISPLAY INVISIBLE (-300 4425);
FORCEPROP 2 LAST SEC 1
J 0
(-300 4425);
DISPLAY 1.106383 (-300 4425);
PAINT MONO (-300 4425);
DISPLAY INVISIBLE (-300 4425);
FORCEPROP 2 LAST CDS_LOCATION C7C18
J 0
(-300 4325);
DISPLAY 0.617021 (-300 4325);
PAINT AQUA (-300 4325);
DISPLAY INVISIBLE (-300 4325);
FORCEPROP 1 LAST PATH I33
J 0
(-300 4375);
DISPLAY 0.978723 (-300 4375);
PAINT WHITE (-300 4375);
DISPLAY INVISIBLE (-300 4375);
FORCEPROP 2 LAST ROOM PVCCIO_CPU0
J 0
(-300 4375);
DISPLAY 2.212766 (-300 4375);
PAINT WHITE (-300 4375);
DISPLAY INVISIBLE (-300 4375);
FORCEPROP 2 LAST CDS_LIB mstr_discrete
J 0
(-350 4225);
DISPLAY 1.617021 (-350 4225);
PAINT ORANGE (-350 4225);
DISPLAY INVISIBLE (-350 4225);
FORCEADD CAP..1
(-1350 4225);
FORCEPROP 1 LAST VALUE 1.0UF
J 0
(-1300 4275);
DISPLAY 0.617021 (-1300 4275);
PAINT SKYBLUE (-1300 4275);
FORCEPROP 1 LAST VOLTAGE 16V
J 0
(-1300 4225);
DISPLAY 0.617021 (-1300 4225);
PAINT SKYBLUE (-1300 4225);
FORCEPROP 1 LAST PACK_TYPE 0402
J 0
(-1300 4025);
DISPLAY 0.617021 (-1300 4025);
PAINT SKYBLUE (-1300 4025);
FORCEPROP 1 LAST TOLERANCE 10%
J 0
(-1300 4175);
DISPLAY 0.617021 (-1300 4175);
PAINT SKYBLUE (-1300 4175);
FORCEPROP 1 LASTPIN (-1350 4125) $PN 2
J 0
(-1340 4105);
DISPLAY 0.617021 (-1340 4105);
PAINT WHITE (-1340 4105);
FORCEPROP 1 LASTPIN (-1350 4325) $PN 1
J 0
(-1340 4305);
DISPLAY 0.617021 (-1340 4305);
PAINT WHITE (-1340 4305);
FORCEPROP 1 LAST MATERIAL X6S
J 0
(-1300 4125);
DISPLAY 0.617021 (-1300 4125);
PAINT SKYBLUE (-1300 4125);
FORCEPROP 1 LAST PART_NUMBER D97712-011
J 0
(-1300 4075);
DISPLAY 0.617021 (-1300 4075);
PAINT BLUE (-1300 4075);
FORCEPROP 1 LAST LOCATION C7C17
J 0
(-1300 4325);
DISPLAY 0.617021 (-1300 4325);
PAINT AQUA (-1300 4325);
FORCEPROP 2 LAST CDS_LIB mstr_discrete
J 0
(-1350 4225);
DISPLAY 1.617021 (-1350 4225);
PAINT ORANGE (-1350 4225);
DISPLAY INVISIBLE (-1350 4225);
FORCEPROP 1 LAST PATH I36
J 0
(-1300 4375);
DISPLAY 0.978723 (-1300 4375);
PAINT WHITE (-1300 4375);
DISPLAY INVISIBLE (-1300 4375);
FORCEPROP 2 LAST CDS_LOCATION C7C17
J 0
(-1300 4325);
DISPLAY 0.617021 (-1300 4325);
PAINT AQUA (-1300 4325);
DISPLAY INVISIBLE (-1300 4325);
FORCEPROP 2 LAST ROOM PVCCIO_CPU0
J 0
(-1300 4375);
DISPLAY 2.212766 (-1300 4375);
PAINT WHITE (-1300 4375);
DISPLAY INVISIBLE (-1300 4375);
FORCEPROP 2 LAST SEC 1
J 0
(-1300 4425);
DISPLAY 1.106383 (-1300 4425);
PAINT MONO (-1300 4425);
DISPLAY INVISIBLE (-1300 4425);
FORCEPROP 2 LAST SEC_TYPE 0402
J 0
(-1300 4425);
DISPLAY 1.659574 (-1300 4425);
PAINT ORANGE (-1300 4425);
DISPLAY INVISIBLE (-1300 4425);
FORCEADD CAP..1
R 2
(-1600 3600);
FORCEPROP 1 LAST VALUE 0.220UF
J 2
(-1650 3650);
DISPLAY 0.617021 (-1650 3650);
PAINT SKYBLUE (-1650 3650);
FORCEPROP 1 LAST PART_NUMBER A36096-104
J 2
(-1650 3450);
DISPLAY 0.617021 (-1650 3450);
PAINT BLUE (-1650 3450);
FORCEPROP 1 LAST VOLTAGE 16V
J 2
(-1650 3600);
DISPLAY 0.617021 (-1650 3600);
PAINT SKYBLUE (-1650 3600);
FORCEPROP 1 LAST TOLERANCE 10%
J 2
(-1650 3550);
DISPLAY 0.617021 (-1650 3550);
PAINT SKYBLUE (-1650 3550);
FORCEPROP 1 LAST MATERIAL X7R
J 2
(-1650 3500);
DISPLAY 0.617021 (-1650 3500);
PAINT SKYBLUE (-1650 3500);
FORCEPROP 1 LASTPIN (-1600 3500) $PN 2
J 2
(-1610 3480);
DISPLAY 0.617021 (-1610 3480);
PAINT ORANGE (-1610 3480);
FORCEPROP 1 LAST PACK_TYPE 0402
J 2
(-1650 3400);
DISPLAY 0.617021 (-1650 3400);
PAINT SKYBLUE (-1650 3400);
FORCEPROP 1 LAST LOCATION C7C14
J 2
(-1650 3700);
DISPLAY 0.617021 (-1650 3700);
PAINT AQUA (-1650 3700);
FORCEPROP 1 LASTPIN (-1600 3700) $PN 1
J 2
(-1610 3680);
DISPLAY 0.617021 (-1610 3680);
PAINT ORANGE (-1610 3680);
FORCEPROP 2 LAST SEC 1
J 0
(-1650 3800);
DISPLAY 0.680851 (-1650 3800);
PAINT MONO (-1650 3800);
DISPLAY INVISIBLE (-1650 3800);
FORCEPROP 2 LAST SEC_TYPE 0402
J 0
(-1650 3800);
DISPLAY 1.021277 (-1650 3800);
PAINT ORANGE (-1650 3800);
DISPLAY INVISIBLE (-1650 3800);
FORCEPROP 0 LAST SPOF TRUE
J 0
(-1650 3800);
DISPLAY 1.021277 (-1650 3800);
PAINT ORANGE (-1650 3800);
DISPLAY INVISIBLE (-1650 3800);
FORCEPROP 2 LAST ROOM PVCCIO_CPU0
J 0
(-1650 3750);
DISPLAY 2.212766 (-1650 3750);
PAINT WHITE (-1650 3750);
DISPLAY INVISIBLE (-1650 3750);
FORCEPROP 1 LAST PATH I37
J 2
(-1650 3750);
DISPLAY 0.978723 (-1650 3750);
PAINT WHITE (-1650 3750);
DISPLAY INVISIBLE (-1650 3750);
FORCEPROP 2 LAST CDS_LOCATION C7C14
J 2
(-1650 3700);
DISPLAY 0.617021 (-1650 3700);
PAINT AQUA (-1650 3700);
DISPLAY INVISIBLE (-1650 3700);
FORCEPROP 2 LAST CDS_LIB mstr_discrete
J 0
(-1600 3600);
PAINT ORANGE (-1600 3600);
DISPLAY INVISIBLE (-1600 3600);
FORCEADD CAP_A..1
(-1650 4225);
FORCEPROP 1 LAST VOLTAGE 16V
J 0
(-1600 4225);
DISPLAY 0.617021 (-1600 4225);
PAINT SKYBLUE (-1600 4225);
FORCEPROP 1 LAST PACK_TYPE 0402V
J 0
(-1600 4025);
DISPLAY 0.617021 (-1600 4025);
PAINT SKYBLUE (-1600 4025);
FORCEPROP 1 LAST MATERIAL X7R
J 0
(-1600 4125);
DISPLAY 0.617021 (-1600 4125);
PAINT SKYBLUE (-1600 4125);
FORCEPROP 1 LAST VALUE 0.1UF
J 0
(-1600 4275);
DISPLAY 0.617021 (-1600 4275);
PAINT SKYBLUE (-1600 4275);
FORCEPROP 1 LAST LOCATION C7C11
J 0
(-1600 4325);
DISPLAY 0.617021 (-1600 4325);
PAINT AQUA (-1600 4325);
FORCEPROP 1 LASTPIN (-1650 4325) $PN 1
J 0
(-1640 4305);
DISPLAY 0.617021 (-1640 4305);
PAINT WHITE (-1640 4305);
FORCEPROP 1 LASTPIN (-1650 4125) $PN 2
J 0
(-1640 4105);
DISPLAY 0.617021 (-1640 4105);
PAINT WHITE (-1640 4105);
FORCEPROP 1 LAST TOLERANCE 10%
J 0
(-1600 4175);
DISPLAY 0.617021 (-1600 4175);
PAINT SKYBLUE (-1600 4175);
FORCEPROP 1 LAST PART_NUMBER A36096-030
J 0
(-1600 4075);
DISPLAY 0.617021 (-1600 4075);
PAINT BLUE (-1600 4075);
FORCEPROP 1 LAST PATH I38
J 0
(-1600 4375);
DISPLAY 0.978723 (-1600 4375);
PAINT WHITE (-1600 4375);
DISPLAY INVISIBLE (-1600 4375);
FORCEPROP 2 LAST CDS_LOCATION C7C11
J 0
(-1600 4325);
DISPLAY 0.617021 (-1600 4325);
PAINT AQUA (-1600 4325);
DISPLAY INVISIBLE (-1600 4325);
FORCEPROP 2 LAST CDS_SEC 1
J 0
(-1600 4375);
PAINT ORANGE (-1600 4375);
DISPLAY INVISIBLE (-1600 4375);
FORCEPROP 2 LAST SEC_TYPE 0402V
J 0
(-1600 4425);
DISPLAY 1.659574 (-1600 4425);
PAINT ORANGE (-1600 4425);
DISPLAY INVISIBLE (-1600 4425);
FORCEPROP 2 LAST SEC 1
J 0
(-1600 4425);
DISPLAY 1.106383 (-1600 4425);
PAINT MONO (-1600 4425);
DISPLAY INVISIBLE (-1600 4425);
FORCEPROP 2 LAST ROOM PVCCIO_CPU0
J 0
(-1600 4375);
DISPLAY 2.212766 (-1600 4375);
PAINT WHITE (-1600 4375);
DISPLAY INVISIBLE (-1600 4375);
FORCEPROP 2 LAST CDS_LIB dev_discrete
J 0
(-1650 4225);
PAINT ORANGE (-1650 4225);
DISPLAY INVISIBLE (-1650 4225);
FORCEADD CAP..1
(-1950 4225);
FORCEPROP 1 LAST LOCATION C7C12
J 0
(-1900 4325);
DISPLAY 0.617021 (-1900 4325);
PAINT AQUA (-1900 4325);
FORCEPROP 1 LASTPIN (-1950 4325) $PN 1
J 0
(-1940 4305);
DISPLAY 0.617021 (-1940 4305);
PAINT WHITE (-1940 4305);
FORCEPROP 1 LASTPIN (-1950 4125) $PN 2
J 0
(-1940 4105);
DISPLAY 0.617021 (-1940 4105);
PAINT WHITE (-1940 4105);
FORCEPROP 1 LAST PACK_TYPE 0402
J 0
(-1900 4025);
DISPLAY 0.617021 (-1900 4025);
PAINT SKYBLUE (-1900 4025);
FORCEPROP 1 LAST PART_NUMBER D97712-011
J 0
(-1900 4075);
DISPLAY 0.617021 (-1900 4075);
PAINT BLUE (-1900 4075);
FORCEPROP 1 LAST TOLERANCE 10%
J 0
(-1900 4175);
DISPLAY 0.617021 (-1900 4175);
PAINT SKYBLUE (-1900 4175);
FORCEPROP 1 LAST VOLTAGE 16V
J 0
(-1900 4225);
DISPLAY 0.617021 (-1900 4225);
PAINT SKYBLUE (-1900 4225);
FORCEPROP 1 LAST VALUE 1.0UF
J 0
(-1900 4275);
DISPLAY 0.617021 (-1900 4275);
PAINT SKYBLUE (-1900 4275);
FORCEPROP 1 LAST MATERIAL X6S
J 0
(-1900 4125);
DISPLAY 0.617021 (-1900 4125);
PAINT SKYBLUE (-1900 4125);
FORCEPROP 2 LAST ROOM PVCCIO_CPU0
J 0
(-1900 4375);
DISPLAY 2.212766 (-1900 4375);
PAINT WHITE (-1900 4375);
DISPLAY INVISIBLE (-1900 4375);
FORCEPROP 1 LAST PATH I39
J 0
(-1900 4375);
DISPLAY 0.978723 (-1900 4375);
PAINT WHITE (-1900 4375);
DISPLAY INVISIBLE (-1900 4375);
FORCEPROP 2 LAST CDS_LOCATION C7C12
J 0
(-1900 4325);
DISPLAY 0.617021 (-1900 4325);
PAINT AQUA (-1900 4325);
DISPLAY INVISIBLE (-1900 4325);
FORCEPROP 2 LAST SEC 1
J 0
(-1900 4425);
DISPLAY 1.106383 (-1900 4425);
PAINT MONO (-1900 4425);
DISPLAY INVISIBLE (-1900 4425);
FORCEPROP 2 LAST SEC_TYPE 0402
J 0
(-1900 4425);
DISPLAY 1.659574 (-1900 4425);
PAINT ORANGE (-1900 4425);
DISPLAY INVISIBLE (-1900 4425);
FORCEPROP 2 LAST CDS_LIB mstr_discrete
J 0
(-1950 4225);
DISPLAY 1.617021 (-1950 4225);
PAINT ORANGE (-1950 4225);
DISPLAY INVISIBLE (-1950 4225);
FORCEADD CAP..1
(-2250 4225);
FORCEPROP 1 LAST LOCATION C3N36
J 0
(-2200 4325);
DISPLAY 0.617021 (-2200 4325);
PAINT AQUA (-2200 4325);
FORCEPROP 1 LASTPIN (-2250 4325) $PN 1
J 0
(-2240 4305);
DISPLAY 0.617021 (-2240 4305);
PAINT WHITE (-2240 4305);
FORCEPROP 1 LAST VALUE 10UF
J 0
(-2200 4275);
DISPLAY 0.617021 (-2200 4275);
PAINT SKYBLUE (-2200 4275);
FORCEPROP 1 LAST VOLTAGE 16V
J 0
(-2200 4225);
DISPLAY 0.617021 (-2200 4225);
PAINT SKYBLUE (-2200 4225);
FORCEPROP 1 LASTPIN (-2250 4125) $PN 2
J 0
(-2240 4105);
DISPLAY 0.617021 (-2240 4105);
PAINT WHITE (-2240 4105);
FORCEPROP 1 LAST PACK_TYPE 0805
J 0
(-2200 4025);
DISPLAY 0.617021 (-2200 4025);
PAINT SKYBLUE (-2200 4025);
FORCEPROP 1 LAST PART_NUMBER C95333-007
J 0
(-2200 4075);
DISPLAY 0.617021 (-2200 4075);
PAINT BLUE (-2200 4075);
FORCEPROP 1 LAST MATERIAL X6S
J 0
(-2200 4125);
DISPLAY 0.617021 (-2200 4125);
PAINT SKYBLUE (-2200 4125);
FORCEPROP 1 LAST TOLERANCE 10%
J 0
(-2200 4175);
DISPLAY 0.617021 (-2200 4175);
PAINT SKYBLUE (-2200 4175);
FORCEPROP 2 LAST ROOM PVCCIO_CPU0
J 0
(-2200 4375);
DISPLAY 2.212766 (-2200 4375);
PAINT WHITE (-2200 4375);
DISPLAY INVISIBLE (-2200 4375);
FORCEPROP 1 LAST PATH I40
J 0
(-2200 4375);
DISPLAY 0.978723 (-2200 4375);
PAINT WHITE (-2200 4375);
DISPLAY INVISIBLE (-2200 4375);
FORCEPROP 2 LAST CDS_LOCATION C3N36
J 0
(-2200 4325);
DISPLAY 0.617021 (-2200 4325);
PAINT AQUA (-2200 4325);
DISPLAY INVISIBLE (-2200 4325);
FORCEPROP 2 LAST SEC 1
J 0
(-2200 4425);
DISPLAY 1.106383 (-2200 4425);
PAINT MONO (-2200 4425);
DISPLAY INVISIBLE (-2200 4425);
FORCEPROP 2 LAST SEC_TYPE 0805
J 0
(-2200 4425);
DISPLAY 1.659574 (-2200 4425);
PAINT ORANGE (-2200 4425);
DISPLAY INVISIBLE (-2200 4425);
FORCEPROP 2 LAST CDS_LIB mstr_discrete
J 0
(-2250 4225);
DISPLAY 1.617021 (-2250 4225);
PAINT ORANGE (-2250 4225);
DISPLAY INVISIBLE (-2250 4225);
FORCEADD CAP..1
(-2475 4225);
FORCEPROP 1 LAST LOCATION C3N33
J 0
(-2425 4325);
DISPLAY 0.617021 (-2425 4325);
PAINT AQUA (-2425 4325);
FORCEPROP 1 LAST VALUE 10UF
J 0
(-2425 4275);
DISPLAY 0.617021 (-2425 4275);
PAINT SKYBLUE (-2425 4275);
FORCEPROP 1 LASTPIN (-2475 4325) $PN 1
J 0
(-2465 4305);
DISPLAY 0.617021 (-2465 4305);
PAINT WHITE (-2465 4305);
FORCEPROP 1 LAST TOLERANCE 10%
J 0
(-2425 4175);
DISPLAY 0.617021 (-2425 4175);
PAINT SKYBLUE (-2425 4175);
FORCEPROP 1 LAST PACK_TYPE 0805
J 0
(-2425 4025);
DISPLAY 0.617021 (-2425 4025);
PAINT SKYBLUE (-2425 4025);
FORCEPROP 1 LAST VOLTAGE 16V
J 0
(-2425 4225);
DISPLAY 0.617021 (-2425 4225);
PAINT SKYBLUE (-2425 4225);
FORCEPROP 1 LAST MATERIAL X6S
J 0
(-2425 4125);
DISPLAY 0.617021 (-2425 4125);
PAINT SKYBLUE (-2425 4125);
FORCEPROP 1 LASTPIN (-2475 4125) $PN 2
J 0
(-2465 4105);
DISPLAY 0.617021 (-2465 4105);
PAINT WHITE (-2465 4105);
FORCEPROP 1 LAST PART_NUMBER C95333-007
J 0
(-2425 4075);
DISPLAY 0.617021 (-2425 4075);
PAINT BLUE (-2425 4075);
FORCEPROP 2 LAST ROOM PVCCIO_CPU0
J 0
(-2425 4375);
DISPLAY 2.212766 (-2425 4375);
PAINT WHITE (-2425 4375);
DISPLAY INVISIBLE (-2425 4375);
FORCEPROP 2 LAST SEC 1
J 0
(-2425 4425);
DISPLAY 1.106383 (-2425 4425);
PAINT MONO (-2425 4425);
DISPLAY INVISIBLE (-2425 4425);
FORCEPROP 1 LAST PATH I41
J 0
(-2425 4375);
DISPLAY 0.978723 (-2425 4375);
PAINT WHITE (-2425 4375);
DISPLAY INVISIBLE (-2425 4375);
FORCEPROP 2 LAST SEC_TYPE 0805
J 0
(-2425 4425);
DISPLAY 1.659574 (-2425 4425);
PAINT ORANGE (-2425 4425);
DISPLAY INVISIBLE (-2425 4425);
FORCEPROP 2 LAST CDS_LOCATION C3N33
J 0
(-2425 4325);
DISPLAY 0.617021 (-2425 4325);
PAINT AQUA (-2425 4325);
DISPLAY INVISIBLE (-2425 4325);
FORCEPROP 2 LAST CDS_LIB mstr_discrete
J 0
(-2475 4225);
DISPLAY 1.617021 (-2475 4225);
PAINT ORANGE (-2475 4225);
DISPLAY INVISIBLE (-2475 4225);
FORCEADD CAP..1
(-2725 4225);
FORCEPROP 1 LAST VALUE 10UF
J 0
(-2675 4275);
DISPLAY 0.617021 (-2675 4275);
PAINT SKYBLUE (-2675 4275);
FORCEPROP 1 LASTPIN (-2725 4325) $PN 1
J 0
(-2715 4305);
DISPLAY 0.617021 (-2715 4305);
PAINT WHITE (-2715 4305);
FORCEPROP 1 LAST VOLTAGE 16V
J 0
(-2675 4225);
DISPLAY 0.617021 (-2675 4225);
PAINT SKYBLUE (-2675 4225);
FORCEPROP 1 LAST MATERIAL X6S
J 0
(-2675 4125);
DISPLAY 0.617021 (-2675 4125);
PAINT SKYBLUE (-2675 4125);
FORCEPROP 1 LASTPIN (-2725 4125) $PN 2
J 0
(-2715 4105);
DISPLAY 0.617021 (-2715 4105);
PAINT WHITE (-2715 4105);
FORCEPROP 1 LAST PART_NUMBER C95333-007
J 0
(-2675 4075);
DISPLAY 0.617021 (-2675 4075);
PAINT BLUE (-2675 4075);
FORCEPROP 1 LAST TOLERANCE 10%
J 0
(-2675 4175);
DISPLAY 0.617021 (-2675 4175);
PAINT SKYBLUE (-2675 4175);
FORCEPROP 1 LAST PACK_TYPE 0805
J 0
(-2675 4025);
DISPLAY 0.617021 (-2675 4025);
PAINT SKYBLUE (-2675 4025);
FORCEPROP 1 LAST LOCATION C3N34
J 0
(-2675 4325);
DISPLAY 0.617021 (-2675 4325);
PAINT AQUA (-2675 4325);
FORCEPROP 2 LAST SEC_TYPE 0805
J 0
(-2675 4425);
DISPLAY 1.659574 (-2675 4425);
PAINT ORANGE (-2675 4425);
DISPLAY INVISIBLE (-2675 4425);
FORCEPROP 2 LAST SEC 1
J 0
(-2675 4425);
DISPLAY 1.106383 (-2675 4425);
PAINT MONO (-2675 4425);
DISPLAY INVISIBLE (-2675 4425);
FORCEPROP 2 LAST ROOM PVCCIO_CPU0
J 0
(-2675 4375);
DISPLAY 2.212766 (-2675 4375);
PAINT WHITE (-2675 4375);
DISPLAY INVISIBLE (-2675 4375);
FORCEPROP 1 LAST PATH I43
J 0
(-2675 4375);
DISPLAY 0.978723 (-2675 4375);
PAINT WHITE (-2675 4375);
DISPLAY INVISIBLE (-2675 4375);
FORCEPROP 2 LAST CDS_LOCATION C3N34
J 0
(-2675 4325);
DISPLAY 0.617021 (-2675 4325);
PAINT AQUA (-2675 4325);
DISPLAY INVISIBLE (-2675 4325);
FORCEPROP 2 LAST CDS_LIB mstr_discrete
J 0
(-2725 4225);
DISPLAY 1.617021 (-2725 4225);
PAINT ORANGE (-2725 4225);
DISPLAY INVISIBLE (-2725 4225);
FORCEADD GND..1
(-2725 3850);
FORCEPROP 3 LASTPIN (-2725 3900) SIG_NAME GND\g
J 0
(-2715 3910);
DISPLAY 0.659574 (-2715 3910);
PAINT MONO (-2715 3910);
DISPLAY INVISIBLE (-2715 3910);
FORCEPROP 2 LAST ROOM PVCCIO_CPU0
J 0
(-3275 3925);
DISPLAY 3.127660 (-3275 3925);
PAINT WHITE (-3275 3925);
DISPLAY INVISIBLE (-3275 3925);
FORCEPROP 2 LAST BOM_COST PROC_VRD_PVCCIO_CPU0
J 0
(-3100 3925);
DISPLAY 2.340426 (-3100 3925);
PAINT WHITE (-3100 3925);
DISPLAY INVISIBLE (-3100 3925);
FORCEPROP 1 LAST PATH I44
J 0
(-2650 3850);
DISPLAY 0.872340 (-2650 3850);
PAINT AQUA (-2650 3850);
DISPLAY INVISIBLE (-2650 3850);
FORCEPROP 1 LAST VOLTAGE 0.0V
J 0
(-2770 3807);
DISPLAY 0.340426 (-2770 3807);
PAINT SKYBLUE (-2770 3807);
DISPLAY INVISIBLE (-2770 3807);
FORCEPROP 2 LAST CDS_LIB mstr_symbols
J 0
(-2725 3850);
DISPLAY 1.617021 (-2725 3850);
PAINT ORANGE (-2725 3850);
DISPLAY INVISIBLE (-2725 3850);
FORCEPROP 1 LAST SIZE 1B
J 0
(-2650 3800);
DISPLAY 2.787234 (-2650 3800);
PAINT GREEN (-2650 3800);
DISPLAY INVISIBLE (-2650 3800);
FORCEPROP 1 LAST BODY_TYPE PLUMBING
J 0
(-2770 3807);
DISPLAY 0.340426 (-2770 3807);
PAINT GREEN (-2770 3807);
DISPLAY INVISIBLE (-2770 3807);
FORCEPROP 1 LAST HDL_POWER GND
J 0
(-2725 4000);
DISPLAY 2.787234 (-2725 4000);
PAINT GREEN (-2725 4000);
DISPLAY INVISIBLE (-2725 4000);
FORCEADD OFFPAGE..1
(-2000 3850);
FORCEPROP 2 LAST $XR0 211 
J 0
(-2282 3850);
DISPLAY 0.638298 (-2282 3850);
PAINT MONO (-2282 3850);
FORCEPROP 2 LAST ROOM PVCCIO_CPU0
J 0
(-2400 3925);
DISPLAY 3.127660 (-2400 3925);
PAINT WHITE (-2400 3925);
DISPLAY INVISIBLE (-2400 3925);
FORCEPROP 2 LAST BOM_COST PROC_VRD_PVCCIO_CPU0
J 0
(-2250 3900);
DISPLAY 2.340426 (-2250 3900);
PAINT WHITE (-2250 3900);
DISPLAY INVISIBLE (-2250 3900);
FORCEPROP 2 LAST PATH I45
J 0
(-2250 3900);
DISPLAY 1.021277 (-2250 3900);
PAINT ORANGE (-2250 3900);
DISPLAY INVISIBLE (-2250 3900);
FORCEPROP 2 LAST CDS_LIB mstr_standard
J 0
(-2000 3850);
DISPLAY 1.617021 (-2000 3850);
PAINT ORANGE (-2000 3850);
DISPLAY INVISIBLE (-2000 3850);
FORCEPROP 1 LAST OFFPAGE TRUE
J 0
(-1675 3725);
PAINT GREEN (-1675 3725);
DISPLAY INVISIBLE (-1675 3725);
FORCEPROP 1 LAST COMMENT_BODY TRUE
J 0
(-1875 3750);
DISPLAY 2.723404 (-1875 3750);
PAINT PEACH (-1875 3750);
DISPLAY INVISIBLE (-1875 3750);
FORCEADD P12V_STBY..1
(-50 2550);
FORCEPROP 3 LASTPIN (-50 2500) SIG_NAME P12V_STBY\g
J 0
(-40 2510);
DISPLAY 0.659574 (-40 2510);
PAINT MONO (-40 2510);
DISPLAY INVISIBLE (-40 2510);
FORCEPROP 1 LAST VOLTAGE 12.0V
J 0
(-95 2507);
DISPLAY 0.340426 (-95 2507);
PAINT SKYBLUE (-95 2507);
DISPLAY INVISIBLE (-95 2507);
FORCEPROP 1 LAST PATH I57
J 0
(-5 2552);
DISPLAY 0.340426 (-5 2552);
PAINT GREEN (-5 2552);
DISPLAY INVISIBLE (-5 2552);
FORCEPROP 2 LAST CDS_LIB mstr_symbols
J 0
(-50 2550);
PAINT ORANGE (-50 2550);
DISPLAY INVISIBLE (-50 2550);
FORCEPROP 1 LAST SIZE 1B
J 0
(-5 2572);
DISPLAY 0.340426 (-5 2572);
PAINT GREEN (-5 2572);
DISPLAY INVISIBLE (-5 2572);
FORCEPROP 1 LAST BODY_TYPE PLUMBING
J 0
(-95 2507);
DISPLAY 0.340426 (-95 2507);
PAINT GREEN (-95 2507);
DISPLAY INVISIBLE (-95 2507);
FORCEPROP 1 LAST HDL_POWER P12V_STBY
J 0
(-350 2425);
DISPLAY 0.872340 (-350 2425);
PAINT ORANGE (-350 2425);
DISPLAY INVISIBLE (-350 2425);
FORCEADD P5V_STBY..1
(0 4875);
FORCEPROP 3 LASTPIN (0 4825) SIG_NAME P5V_STBY\g
J 0
(10 4835);
DISPLAY 0.659574 (10 4835);
PAINT MONO (10 4835);
DISPLAY INVISIBLE (10 4835);
FORCEPROP 1 LAST VOLTAGE 5.0V
J 0
(-45 4832);
DISPLAY 0.340426 (-45 4832);
PAINT SKYBLUE (-45 4832);
DISPLAY INVISIBLE (-45 4832);
FORCEPROP 1 LAST PATH I58
J 0
(45 4877);
DISPLAY 0.340426 (45 4877);
PAINT GREEN (45 4877);
DISPLAY INVISIBLE (45 4877);
FORCEPROP 2 LAST CDS_LIB mstr_symbols
J 0
(0 4875);
PAINT ORANGE (0 4875);
DISPLAY INVISIBLE (0 4875);
FORCEPROP 1 LAST SIZE 1B
J 0
(45 4897);
DISPLAY 0.340426 (45 4897);
PAINT GREEN (45 4897);
DISPLAY INVISIBLE (45 4897);
FORCEPROP 1 LAST BODY_TYPE PLUMBING
J 0
(-45 4832);
DISPLAY 0.340426 (-45 4832);
PAINT GREEN (-45 4832);
DISPLAY INVISIBLE (-45 4832);
FORCEPROP 1 LAST HDL_POWER P5V_STBY
J 0
(-300 4750);
DISPLAY 0.872340 (-300 4750);
PAINT ORANGE (-300 4750);
DISPLAY INVISIBLE (-300 4750);
FORCEADD OFFPAGE..1
(-3225 1400);
FORCEPROP 2 LAST $XR0 39 
J 0
(-3476 1400);
DISPLAY 0.638298 (-3476 1400);
PAINT MONO (-3476 1400);
FORCEPROP 2 LAST CDS_LIB mstr_standard
J 0
(-3225 1400);
PAINT ORANGE (-3225 1400);
DISPLAY INVISIBLE (-3225 1400);
FORCEPROP 2 LAST BOM_COST PROC_VRD_VCCIN_CPU0
J 0
(-3425 1450);
PAINT MONO (-3425 1450);
DISPLAY INVISIBLE (-3425 1450);
FORCEPROP 2 LAST PATH I59
J 0
(-3425 1450);
DISPLAY 1.021277 (-3425 1450);
PAINT ORANGE (-3425 1450);
DISPLAY INVISIBLE (-3425 1450);
FORCEPROP 2 LAST ROOM VCCIN_CPU0_DECAP_VR
J 0
(-3750 1475);
PAINT ORANGE (-3750 1475);
DISPLAY INVISIBLE (-3750 1475);
FORCEPROP 1 LAST OFFPAGE TRUE
J 0
(-2900 1275);
DISPLAY 0.893617 (-2900 1275);
PAINT GREEN (-2900 1275);
DISPLAY INVISIBLE (-2900 1275);
FORCEPROP 1 LAST COMMENT_BODY TRUE
J 0
(-3100 1300);
DISPLAY 0.893617 (-3100 1300);
PAINT GREEN (-3100 1300);
DISPLAY INVISIBLE (-3100 1300);
FORCEADD CAP_A..1
(-1925 1675);
FORCEPROP 1 LASTPIN (-1925 1775) $PN 1
J 0
(-1915 1755);
DISPLAY 0.787234 (-1915 1755);
PAINT ORANGE (-1915 1755);
FORCEPROP 1 LASTPIN (-1925 1575) $PN 2
J 0
(-1915 1555);
DISPLAY 0.787234 (-1915 1555);
PAINT ORANGE (-1915 1555);
FORCEPROP 1 LAST LOCATION C3P1
J 0
(-1875 1775);
DISPLAY 0.617021 (-1875 1775);
PAINT AQUA (-1875 1775);
FORCEPROP 1 LAST VALUE 0.1UF
J 0
(-1875 1725);
DISPLAY 0.617021 (-1875 1725);
PAINT SKYBLUE (-1875 1725);
FORCEPROP 1 LAST VOLTAGE 16V
J 0
(-1875 1675);
DISPLAY 0.617021 (-1875 1675);
PAINT SKYBLUE (-1875 1675);
FORCEPROP 1 LAST TOLERANCE 10%
J 0
(-1875 1625);
DISPLAY 0.617021 (-1875 1625);
PAINT SKYBLUE (-1875 1625);
FORCEPROP 1 LAST MATERIAL EMPTY
J 0
(-1875 1575);
DISPLAY 0.617021 (-1875 1575);
PAINT RED (-1875 1575);
FORCEPROP 1 LAST PART_NUMBER A36096-030
J 0
(-1875 1525);
DISPLAY 0.617021 (-1875 1525);
PAINT BLUE (-1875 1525);
FORCEPROP 1 LAST PACK_TYPE 0402V
J 0
(-1875 1475);
DISPLAY 0.617021 (-1875 1475);
PAINT SKYBLUE (-1875 1475);
FORCEPROP 2 LAST SEC_TYPE 0402V
J 0
(-1875 1875);
DISPLAY 1.021277 (-1875 1875);
PAINT ORANGE (-1875 1875);
DISPLAY INVISIBLE (-1875 1875);
FORCEPROP 0 LAST SEC 1
J 0
(-1875 1825);
DISPLAY 0.680851 (-1875 1825);
PAINT MONO (-1875 1825);
DISPLAY INVISIBLE (-1875 1825);
FORCEPROP 2 LAST ROOM PVCCIO_CPU0
J 0
(-1875 1825);
DISPLAY 0.723404 (-1875 1825);
PAINT ORANGE (-1875 1825);
DISPLAY INVISIBLE (-1875 1825);
FORCEPROP 1 LAST PATH I60
J 0
(-1875 1825);
DISPLAY 0.978723 (-1875 1825);
PAINT WHITE (-1875 1825);
DISPLAY INVISIBLE (-1875 1825);
FORCEPROP 2 LAST BOM_COST PROC_VRD_PVCCIO_CPU0
J 0
(-1875 1825);
DISPLAY 0.723404 (-1875 1825);
PAINT ORANGE (-1875 1825);
DISPLAY INVISIBLE (-1875 1825);
FORCEPROP 2 LAST CDS_LOCATION C3P1
J 0
(-1875 1775);
DISPLAY 0.617021 (-1875 1775);
PAINT AQUA (-1875 1775);
DISPLAY INVISIBLE (-1875 1775);
FORCEPROP 2 LAST CDS_LIB dev_discrete
J 0
(-1925 1675);
PAINT ORANGE (-1925 1675);
DISPLAY INVISIBLE (-1925 1675);
FORCEADD OFFPAGE..1
(-3250 1850);
FORCEPROP 2 LAST $XR0 39 
J 0
(-3471 1850);
DISPLAY 0.638298 (-3471 1850);
PAINT MONO (-3471 1850);
FORCEPROP 2 LAST CDS_LIB mstr_standard
J 2
(-3250 1850);
PAINT ORANGE (-3250 1850);
DISPLAY INVISIBLE (-3250 1850);
FORCEPROP 2 LAST BOM_COST PROC_VRD_VCCIN_CPU0
J 0
(-3450 1900);
PAINT MONO (-3450 1900);
DISPLAY INVISIBLE (-3450 1900);
FORCEPROP 2 LAST PATH I61
J 0
(-3450 1900);
DISPLAY 1.021277 (-3450 1900);
PAINT ORANGE (-3450 1900);
DISPLAY INVISIBLE (-3450 1900);
FORCEPROP 2 LAST ROOM VCCIN_CPU0_DECAP_VR
J 0
(-3775 1925);
PAINT ORANGE (-3775 1925);
DISPLAY INVISIBLE (-3775 1925);
FORCEPROP 1 LAST OFFPAGE TRUE
J 0
(-2925 1725);
DISPLAY 0.893617 (-2925 1725);
PAINT GREEN (-2925 1725);
DISPLAY INVISIBLE (-2925 1725);
FORCEPROP 1 LAST COMMENT_BODY TRUE
J 0
(-3125 1750);
DISPLAY 0.893617 (-3125 1750);
PAINT GREEN (-3125 1750);
DISPLAY INVISIBLE (-3125 1750);
FORCEADD RES..1
(-725 1150);
FORCEPROP 1 LAST PACK_TYPE 0402
J 0
(-675 1075);
DISPLAY 0.617021 (-675 1075);
PAINT SKYBLUE (-675 1075);
FORCEPROP 1 LAST MATERIAL CHIP
J 0
(-675 1025);
DISPLAY 0.617021 (-675 1025);
PAINT SKYBLUE (-675 1025);
FORCEPROP 1 LASTPIN (-625 1150) $PN 2
J 0
(-663 1162);
DISPLAY 0.787234 (-663 1162);
PAINT WHITE (-663 1162);
FORCEPROP 1 LAST LOCATION R3N20
J 0
(-775 1200);
DISPLAY 0.617021 (-775 1200);
PAINT AQUA (-775 1200);
FORCEPROP 1 LAST TOLERANCE 1%
J 0
(-900 1075);
DISPLAY 0.617021 (-900 1075);
PAINT SKYBLUE (-900 1075);
FORCEPROP 1 LASTPIN (-825 1150) $PN 1
J 0
(-813 1162);
DISPLAY 0.787234 (-813 1162);
PAINT WHITE (-813 1162);
FORCEPROP 1 LAST VALUE 100.0
J 2
(-725 1075);
DISPLAY 0.617021 (-725 1075);
PAINT SKYBLUE (-725 1075);
FORCEPROP 1 LAST WATTAGE 1/16W
J 2
(-700 1025);
DISPLAY 0.617021 (-700 1025);
PAINT SKYBLUE (-700 1025);
FORCEPROP 1 LAST PART_NUMBER G21796-017
J 0
(-875 975);
DISPLAY 0.617021 (-875 975);
PAINT BLUE (-875 975);
FORCEPROP 2 LAST SEC_TYPE 0402
J 0
(-775 1350);
DISPLAY 1.021277 (-775 1350);
PAINT ORANGE (-775 1350);
DISPLAY INVISIBLE (-775 1350);
FORCEPROP 2 LAST SEC 1
J 0
(-755 1370);
DISPLAY 0.680851 (-755 1370);
PAINT MONO (-755 1370);
DISPLAY INVISIBLE (-755 1370);
FORCEPROP 2 LAST CDS_LIB mstr_discrete
J 0
(-725 1150);
PAINT ORANGE (-725 1150);
DISPLAY INVISIBLE (-725 1150);
FORCEPROP 1 LAST PATH I68
J 0
(-775 1300);
DISPLAY 0.978723 (-775 1300);
PAINT WHITE (-775 1300);
DISPLAY INVISIBLE (-775 1300);
FORCEPROP 2 LAST ROOM PVCCIO_CPU0
J 0
(-775 1300);
DISPLAY 0.723404 (-775 1300);
PAINT ORANGE (-775 1300);
DISPLAY INVISIBLE (-775 1300);
FORCEPROP 0 LAST BOM_COST PROC_VRD_PVCCIO_CPU0
J 0
(-775 1250);
DISPLAY 0.723404 (-775 1250);
PAINT ORANGE (-775 1250);
DISPLAY INVISIBLE (-775 1250);
FORCEPROP 2 LAST CDS_LOCATION R3N20
J 0
(-775 1200);
DISPLAY 0.617021 (-775 1200);
PAINT AQUA (-775 1200);
DISPLAY INVISIBLE (-775 1200);
FORCEADD GND..1
(-450 925);
FORCEPROP 3 LASTPIN (-450 975) SIG_NAME GND\g
J 0
(-440 985);
DISPLAY 0.659574 (-440 985);
PAINT MONO (-440 985);
DISPLAY INVISIBLE (-440 985);
FORCEPROP 2 LAST ROOM PVCCIO_CPU0
J 0
(-750 1000);
DISPLAY 0.723404 (-750 1000);
PAINT ORANGE (-750 1000);
DISPLAY INVISIBLE (-750 1000);
FORCEPROP 2 LAST BOM_COST MEM_VRD_PVCCIO_CPU0
J 0
(-950 1000);
DISPLAY 0.723404 (-950 1000);
PAINT ORANGE (-950 1000);
DISPLAY INVISIBLE (-950 1000);
FORCEPROP 2 LAST CDS_LIB mstr_symbols
J 0
(-450 925);
PAINT ORANGE (-450 925);
DISPLAY INVISIBLE (-450 925);
FORCEPROP 1 LAST SIZE 1B
J 0
(-375 875);
DISPLAY 0.638298 (-375 875);
PAINT GREEN (-375 875);
DISPLAY INVISIBLE (-375 875);
FORCEPROP 1 LAST PATH I69
J 0
(-375 925);
DISPLAY 0.872340 (-375 925);
PAINT AQUA (-375 925);
DISPLAY INVISIBLE (-375 925);
FORCEPROP 1 LAST VOLTAGE 0
J 0
(-450 925);
DISPLAY 0.723404 (-450 925);
PAINT SKYBLUE (-450 925);
DISPLAY INVISIBLE (-450 925);
FORCEPROP 1 LAST BODY_TYPE PLUMBING
J 0
(-495 882);
DISPLAY 0.340426 (-495 882);
PAINT GREEN (-495 882);
DISPLAY INVISIBLE (-495 882);
FORCEPROP 1 LAST HDL_POWER GND
J 0
(-450 1075);
DISPLAY 0.638298 (-450 1075);
PAINT GREEN (-450 1075);
DISPLAY INVISIBLE (-450 1075);
FORCEADD OFFPAGE..2
(-225 1400);
FORCEPROP 2 LAST $XR0 211 
J 0
(-36 1400);
DISPLAY 0.638298 (-36 1400);
PAINT MONO (-36 1400);
FORCEPROP 2 LAST ROOM PVCCIO_CPU0
J 0
(50 1425);
DISPLAY 0.617021 (50 1425);
PAINT ORANGE (50 1425);
DISPLAY INVISIBLE (50 1425);
FORCEPROP 2 LAST PATH I70
J 0
(-25 1450);
DISPLAY 1.021277 (-25 1450);
PAINT ORANGE (-25 1450);
DISPLAY INVISIBLE (-25 1450);
FORCEPROP 2 LAST CDS_LIB mstr_standard
J 0
(-225 1400);
PAINT ORANGE (-225 1400);
DISPLAY INVISIBLE (-225 1400);
FORCEPROP 1 LAST OFFPAGE TRUE
J 0
(100 1275);
DISPLAY 0.872340 (100 1275);
PAINT GREEN (100 1275);
DISPLAY INVISIBLE (100 1275);
FORCEPROP 1 LAST COMMENT_BODY TRUE
J 0
(-270 1305);
DISPLAY 0.872340 (-270 1305);
PAINT GREEN (-270 1305);
DISPLAY INVISIBLE (-270 1305);
FORCEADD RES..1
(-725 2325);
FORCEPROP 1 LASTPIN (-825 2325) $PN 1
J 0
(-813 2337);
DISPLAY 0.787234 (-813 2337);
PAINT WHITE (-813 2337);
FORCEPROP 1 LASTPIN (-625 2325) $PN 2
J 0
(-663 2337);
DISPLAY 0.787234 (-663 2337);
PAINT WHITE (-663 2337);
FORCEPROP 1 LAST LOCATION R3N21
J 0
(-775 2375);
DISPLAY 0.617021 (-775 2375);
PAINT AQUA (-775 2375);
FORCEPROP 1 LAST TOLERANCE 1%
J 0
(-900 2250);
DISPLAY 0.617021 (-900 2250);
PAINT SKYBLUE (-900 2250);
FORCEPROP 1 LAST VALUE 100.0
J 2
(-725 2250);
DISPLAY 0.617021 (-725 2250);
PAINT SKYBLUE (-725 2250);
FORCEPROP 1 LAST PACK_TYPE 0402
J 0
(-675 2250);
DISPLAY 0.617021 (-675 2250);
PAINT SKYBLUE (-675 2250);
FORCEPROP 1 LAST MATERIAL CHIP
J 0
(-675 2200);
DISPLAY 0.617021 (-675 2200);
PAINT SKYBLUE (-675 2200);
FORCEPROP 1 LAST WATTAGE 1/16W
J 2
(-700 2200);
DISPLAY 0.617021 (-700 2200);
PAINT SKYBLUE (-700 2200);
FORCEPROP 1 LAST PART_NUMBER G21796-017
J 0
(-875 2150);
DISPLAY 0.617021 (-875 2150);
PAINT BLUE (-875 2150);
FORCEPROP 2 LAST SEC_TYPE 0402
J 0
(-775 2525);
DISPLAY 1.021277 (-775 2525);
PAINT ORANGE (-775 2525);
DISPLAY INVISIBLE (-775 2525);
FORCEPROP 2 LAST SEC 1
J 0
(-761 2545);
DISPLAY 0.680851 (-761 2545);
PAINT MONO (-761 2545);
DISPLAY INVISIBLE (-761 2545);
FORCEPROP 2 LAST CDS_LIB mstr_discrete
J 0
(-725 2325);
PAINT ORANGE (-725 2325);
DISPLAY INVISIBLE (-725 2325);
FORCEPROP 1 LAST LOCATION R3N21
J 0
(-775 2375);
DISPLAY 0.978723 (-775 2375);
PAINT AQUA (-775 2375);
DISPLAY INVISIBLE (-775 2375);
FORCEPROP 2 LAST ROOM PVCCIO_CPU0
J 0
(-775 2475);
DISPLAY 0.723404 (-775 2475);
PAINT ORANGE (-775 2475);
DISPLAY INVISIBLE (-775 2475);
FORCEPROP 1 LAST PATH I74
J 0
(-775 2475);
DISPLAY 0.978723 (-775 2475);
PAINT WHITE (-775 2475);
DISPLAY INVISIBLE (-775 2475);
FORCEPROP 2 LAST CDS_LOCATION R3N21
J 0
(-775 2375);
DISPLAY 0.617021 (-775 2375);
PAINT AQUA (-775 2375);
DISPLAY INVISIBLE (-775 2375);
FORCEPROP 0 LAST BOM_COST PROC_VRD_PVCCIO_CPU0
J 0
(-775 2425);
DISPLAY 0.723404 (-775 2425);
PAINT ORANGE (-775 2425);
DISPLAY INVISIBLE (-775 2425);
FORCEPROP 2 LAST CDS_LOCATION R3N21
J 0
(-775 2375);
DISPLAY 0.978723 (-775 2375);
PAINT AQUA (-775 2375);
DISPLAY INVISIBLE (-775 2375);
FORCEADD PVCCIO_CPU0..1
(-500 2525);
FORCEPROP 3 LASTPIN (-500 2475) SIG_NAME PVCCIO_CPU0\g
J 0
(-490 2485);
DISPLAY 0.659574 (-490 2485);
PAINT MONO (-490 2485);
DISPLAY INVISIBLE (-490 2485);
FORCEPROP 1 LAST VOLTAGE 1.1V
J 0
(-545 2482);
DISPLAY 0.340426 (-545 2482);
PAINT SKYBLUE (-545 2482);
DISPLAY INVISIBLE (-545 2482);
FORCEPROP 1 LAST PATH I75
J 0
(-450 2550);
DISPLAY 0.872340 (-450 2550);
PAINT AQUA (-450 2550);
DISPLAY INVISIBLE (-450 2550);
FORCEPROP 2 LAST CDS_LIB mstr_symbols
J 0
(-500 2525);
PAINT ORANGE (-500 2525);
DISPLAY INVISIBLE (-500 2525);
FORCEPROP 1 LAST BODY_TYPE PLUMBING
J 0
(-545 2482);
DISPLAY 0.340426 (-545 2482);
PAINT GREEN (-545 2482);
DISPLAY INVISIBLE (-545 2482);
FORCEPROP 1 LAST HDL_POWER PVCCIO_CPU0
J 1
(-500 2575);
DISPLAY 0.872340 (-500 2575);
PAINT GREEN (-500 2575);
DISPLAY INVISIBLE (-500 2575);
FORCEADD OFFPAGE..2
(-250 1850);
FORCEPROP 2 LAST $XR0 211 
J 0
(-61 1850);
DISPLAY 0.638298 (-61 1850);
PAINT MONO (-61 1850);
FORCEPROP 2 LAST ROOM PVCCIO_CPU0
J 0
(25 1875);
DISPLAY 0.617021 (25 1875);
PAINT ORANGE (25 1875);
DISPLAY INVISIBLE (25 1875);
FORCEPROP 2 LAST PATH I76
J 0
(-50 1900);
DISPLAY 1.021277 (-50 1900);
PAINT ORANGE (-50 1900);
DISPLAY INVISIBLE (-50 1900);
FORCEPROP 2 LAST CDS_LIB mstr_standard
J 0
(-250 1850);
PAINT ORANGE (-250 1850);
DISPLAY INVISIBLE (-250 1850);
FORCEPROP 1 LAST OFFPAGE TRUE
J 0
(75 1725);
DISPLAY 0.872340 (75 1725);
PAINT GREEN (75 1725);
DISPLAY INVISIBLE (75 1725);
FORCEPROP 1 LAST COMMENT_BODY TRUE
J 0
(-295 1755);
DISPLAY 0.872340 (-295 1755);
PAINT GREEN (-295 1755);
DISPLAY INVISIBLE (-295 1755);
FORCEADD CAP_A..1
(3650 3450);
FORCEPROP 1 LAST LOCATION C7C10
J 0
(3700 3550);
DISPLAY 0.617021 (3700 3550);
PAINT AQUA (3700 3550);
FORCEPROP 1 LAST VALUE 22.0UF
J 0
(3700 3500);
DISPLAY 0.617021 (3700 3500);
PAINT SKYBLUE (3700 3500);
FORCEPROP 1 LAST VOLTAGE 4V
J 0
(3700 3450);
DISPLAY 0.617021 (3700 3450);
PAINT SKYBLUE (3700 3450);
FORCEPROP 1 LASTPIN (3650 3550) $PN 1
J 0
(3660 3530);
DISPLAY 0.617021 (3660 3530);
PAINT ORANGE (3660 3530);
FORCEPROP 1 LASTPIN (3650 3350) $PN 2
J 0
(3660 3330);
DISPLAY 0.617021 (3660 3330);
PAINT ORANGE (3660 3330);
FORCEPROP 1 LAST TOLERANCE 20%
J 0
(3700 3400);
DISPLAY 0.617021 (3700 3400);
PAINT SKYBLUE (3700 3400);
FORCEPROP 1 LAST PACK_TYPE 0603V
J 0
(3700 3250);
DISPLAY 0.617021 (3700 3250);
PAINT SKYBLUE (3700 3250);
FORCEPROP 1 LAST PART_NUMBER E15431-004
J 0
(3700 3300);
DISPLAY 0.617021 (3700 3300);
PAINT BLUE (3700 3300);
FORCEPROP 1 LAST MATERIAL X6S
J 0
(3700 3350);
DISPLAY 0.617021 (3700 3350);
PAINT SKYBLUE (3700 3350);
FORCEPROP 0 LAST GROUP PWR_MLCC_CAP
J 0
(3706 3137);
DISPLAY 0.638298 (3706 3137);
PAINT BROWN (3706 3137);
DISPLAY BOTH (3706 3137);
FORCEPROP 2 LAST CDS_LIB dev_discrete
J 0
(3650 3450);
PAINT ORANGE (3650 3450);
DISPLAY INVISIBLE (3650 3450);
FORCEPROP 2 LAST SEC 1
J 0
(3700 3650);
DISPLAY 0.680851 (3700 3650);
PAINT MONO (3700 3650);
DISPLAY INVISIBLE (3700 3650);
FORCEPROP 2 LAST SEC_TYPE 0603V
J 0
(3700 3650);
DISPLAY 1.021277 (3700 3650);
PAINT ORANGE (3700 3650);
DISPLAY INVISIBLE (3700 3650);
FORCEPROP 1 LAST PATH I77
J 0
(3700 3600);
DISPLAY 0.978723 (3700 3600);
PAINT WHITE (3700 3600);
DISPLAY INVISIBLE (3700 3600);
FORCEPROP 2 LAST CDS_SEC 1
J 0
(3700 3600);
PAINT ORANGE (3700 3600);
DISPLAY INVISIBLE (3700 3600);
FORCEPROP 2 LAST CDS_LOCATION C7C10
J 0
(3700 3550);
DISPLAY 0.617021 (3700 3550);
PAINT AQUA (3700 3550);
DISPLAY INVISIBLE (3700 3550);
FORCEADD RES..2
(4025 3450);
FORCEPROP 1 LAST WATTAGE 1/16W
J 0
(4065 3425);
DISPLAY 0.617021 (4065 3425);
PAINT SKYBLUE (4065 3425);
FORCEPROP 1 LAST MATERIAL CHIP
J 0
(4065 3375);
DISPLAY 0.617021 (4065 3375);
PAINT SKYBLUE (4065 3375);
FORCEPROP 1 LAST PART_NUMBER G21796-208
J 0
(4065 3325);
DISPLAY 0.617021 (4065 3325);
PAINT BLUE (4065 3325);
FORCEPROP 1 LAST PACK_TYPE 0402
J 0
(4065 3275);
DISPLAY 0.617021 (4065 3275);
PAINT SKYBLUE (4065 3275);
FORCEPROP 1 LASTPIN (4025 3350) $PN 2
J 0
(4030 3360);
DISPLAY 0.617021 (4030 3360);
PAINT ORANGE (4030 3360);
FORCEPROP 1 LASTPIN (4025 3550) $PN 1
J 0
(4030 3512);
DISPLAY 0.617021 (4030 3512);
PAINT ORANGE (4030 3512);
FORCEPROP 1 LAST VALUE 51.1
J 0
(4070 3525);
DISPLAY 0.617021 (4070 3525);
PAINT SKYBLUE (4070 3525);
FORCEPROP 1 LAST TOLERANCE 1.0%
J 0
(4070 3475);
DISPLAY 0.617021 (4070 3475);
PAINT SKYBLUE (4070 3475);
FORCEPROP 1 LAST LOCATION R7C3
J 0
(4070 3575);
DISPLAY 0.617021 (4070 3575);
PAINT AQUA (4070 3575);
FORCEPROP 2 LAST CDS_LIB mstr_discrete
J 0
(4025 3450);
PAINT ORANGE (4025 3450);
DISPLAY INVISIBLE (4025 3450);
FORCEPROP 2 LAST CDS_LOCATION R7C3
J 0
(4070 3575);
DISPLAY 0.617021 (4070 3575);
PAINT AQUA (4070 3575);
DISPLAY INVISIBLE (4070 3575);
FORCEPROP 1 LAST PATH I78
J 0
(4075 3625);
DISPLAY 0.978723 (4075 3625);
PAINT WHITE (4075 3625);
DISPLAY INVISIBLE (4075 3625);
FORCEPROP 2 LAST SEC_TYPE 0402
J 0
(4075 3675);
DISPLAY 1.021277 (4075 3675);
PAINT ORANGE (4075 3675);
DISPLAY INVISIBLE (4075 3675);
FORCEPROP 2 LAST SEC 1
J 0
(4075 3675);
DISPLAY 0.680851 (4075 3675);
PAINT MONO (4075 3675);
DISPLAY INVISIBLE (4075 3675);
FORCEADD VCC_CORE..1
(-2725 4750);
FORCEPROP 3 LASTPIN (-2725 4700) SIG_NAME VR_FET_SW_P12V_STBY_PVCCIO_CPU0\g
J 0
(-2715 4710);
DISPLAY 0.659574 (-2715 4710);
PAINT MONO (-2715 4710);
DISPLAY INVISIBLE (-2715 4710);
FORCEPROP 1 LAST HDL_POWER VR_FET_SW_P12V_STBY_PVCCIO_CPU0
J 1
(-2675 4800);
DISPLAY 0.617021 (-2675 4800);
PAINT GREEN (-2675 4800);
FORCEPROP 1 LAST PATH I79
J 0
(-2675 4775);
DISPLAY 0.872340 (-2675 4775);
PAINT AQUA (-2675 4775);
DISPLAY INVISIBLE (-2675 4775);
FORCEPROP 2 LAST CDS_LIB mstr_symbols
J 0
(-2725 4750);
PAINT MONO (-2725 4750);
DISPLAY INVISIBLE (-2725 4750);
FORCEADD VCC_CORE..1
(2900 2650);
FORCEPROP 3 LASTPIN (2900 2600) SIG_NAME VR_FET_SW_P12V_STBY_PVCCIO_CPU0\g
J 0
(2910 2610);
DISPLAY 0.659574 (2910 2610);
PAINT MONO (2910 2610);
DISPLAY INVISIBLE (2910 2610);
FORCEPROP 1 LAST HDL_POWER VR_FET_SW_P12V_STBY_PVCCIO_CPU0
J 1
(2950 2700);
DISPLAY 0.617021 (2950 2700);
PAINT GREEN (2950 2700);
FORCEPROP 1 LAST PATH I80
J 0
(2950 2675);
DISPLAY 0.872340 (2950 2675);
PAINT AQUA (2950 2675);
DISPLAY INVISIBLE (2950 2675);
FORCEPROP 2 LAST CDS_LIB mstr_symbols
J 0
(2900 2650);
PAINT MONO (2900 2650);
DISPLAY INVISIBLE (2900 2650);
FORCEADD PVCCIO_CPU0..1
(850 1600);
FORCEPROP 3 LASTPIN (850 1550) SIG_NAME PVCCIO_CPU0\g
J 0
(860 1560);
DISPLAY 0.659574 (860 1560);
PAINT MONO (860 1560);
DISPLAY INVISIBLE (860 1560);
FORCEPROP 1 LAST VOLTAGE 1.1V
J 0
(805 1557);
DISPLAY 0.340426 (805 1557);
PAINT SKYBLUE (805 1557);
DISPLAY INVISIBLE (805 1557);
FORCEPROP 2 LAST CDS_LIB mstr_symbols
J 0
(850 1600);
PAINT ORANGE (850 1600);
DISPLAY INVISIBLE (850 1600);
FORCEPROP 1 LAST PATH I82
J 0
(900 1625);
DISPLAY 0.872340 (900 1625);
PAINT AQUA (900 1625);
DISPLAY INVISIBLE (900 1625);
FORCEPROP 1 LAST BODY_TYPE PLUMBING
J 0
(805 1557);
DISPLAY 0.340426 (805 1557);
PAINT GREEN (805 1557);
DISPLAY INVISIBLE (805 1557);
FORCEPROP 1 LAST HDL_POWER PVCCIO_CPU0
J 1
(850 1650);
DISPLAY 0.872340 (850 1650);
PAINT GREEN (850 1650);
DISPLAY INVISIBLE (850 1650);
FORCEADD DNS..3
(-1295 1845);
PAINT RED (-1295 1845);
FORCEPROP 2 LAST CDS_LIB mstr_misc
J 0
(-1295 1845);
PAINT ORANGE (-1295 1845);
DISPLAY INVISIBLE (-1295 1845);
FORCEPROP 1 LAST COMMENT_BODY TRUE
R 1
J 0
(-1220 1620);
DISPLAY 0.872340 (-1220 1620);
PAINT GREEN (-1220 1620);
DISPLAY INVISIBLE (-1220 1620);
FORCEADD DNS..2
(3530 4120);
PAINT RED (3530 4120);
FORCEPROP 2 LAST CDS_LIB mstr_misc
J 0
(3530 4120);
PAINT ORANGE (3530 4120);
DISPLAY INVISIBLE (3530 4120);
FORCEPROP 1 LAST COMMENT_BODY TRUE
R 1
J 0
(3605 3895);
DISPLAY 0.872340 (3605 3895);
PAINT GREEN (3605 3895);
DISPLAY INVISIBLE (3605 3895);
FORCEADD DNS..3
(-1295 1395);
PAINT RED (-1295 1395);
FORCEPROP 2 LAST CDS_LIB mstr_misc
J 0
(-1295 1395);
PAINT ORANGE (-1295 1395);
DISPLAY INVISIBLE (-1295 1395);
FORCEPROP 1 LAST COMMENT_BODY TRUE
R 1
J 0
(-1220 1170);
DISPLAY 0.872340 (-1220 1170);
PAINT GREEN (-1220 1170);
DISPLAY INVISIBLE (-1220 1170);
FORCEADD INTEL_CORP_BPAGE..1
(4275 100);
FORCEPROP 1 LAST CDS_CON_LAST_MODIFIED Fri Jun 16 17:49:17 2017
J 0
(2850 425);
PAINT ORANGE (2850 425);
DISPLAY INVISIBLE (2850 425);
FORCEPROP 1 LAST CUSTOM_TXT_CDS <CURRENT_DESIGN_SHEET> OF <TOTAL_DESIGN_SHEETS>
J 0
(3775 125);
PAINT ORANGE (3775 125);
FORCEPROP 1 LAST CUSTOM_TXT_CDS <CON_LAST_MODIFIED>
J 0
(275 200);
PAINT ORANGE (275 200);
FORCEPROP 2 LAST CUSTOM_TXT_CDS <XR_PAGE_TITLE>
J 0
(-3615 5350);
DISPLAY 0.638298 (-3615 5350);
PAINT PINK (-3615 5350);
DISPLAY INVISIBLE (-3615 5350);
FORCEPROP 1 LAST SCH_TITLE PVCCIO CPU0 (2 OF 2)
J 0
(-3675 150);
DISPLAY 1.212766 (-3675 150);
PAINT ORANGE (-3675 150);
FORCEPROP 2 LAST CDS_LIB mstr_symbols
J 0
(4275 100);
PAINT MONO (4275 100);
DISPLAY INVISIBLE (4275 100);
FORCEPROP 2 LAST PAGE_BORDER TRUE
J 0
(-3615 5350);
DISPLAY 0.638298 (-3615 5350);
PAINT PINK (-3615 5350);
DISPLAY INVISIBLE (-3615 5350);
FORCEPROP 1 LAST COMMENT_BODY TRUE
J 0
(4287 112);
DISPLAY 0.468085 (4287 112);
PAINT GREEN (4287 112);
DISPLAY INVISIBLE (4287 112);
FORCEPROP 2 LAST CDS_XR_PAGE_TITLE CR-212 : @BASEBOARD_FAB2_LIB.BASEBOARD_FAB2(SCH_1):PAGE212
J 0
(-3615 5350);
DISPLAY 0.638298 (-3615 5350);
PAINT PINK (-3615 5350);
DISPLAY INVISIBLE (-3615 5350);
FORCEADD DESIGN_NOTE..1
(-3100 2575);
PAINT PURPLE (-3100 2575);
FORCEPROP 2 LAST CDS_LIB mstr_symbols
J 0
(-3100 2575);
PAINT ORANGE (-3100 2575);
DISPLAY INVISIBLE (-3100 2575);
FORCEPROP 2 LAST BOM_COST SM_CONTROLLER
J 0
(-3300 2525);
PAINT MONO (-3300 2525);
DISPLAY INVISIBLE (-3300 2525);
FORCEPROP 2 LAST ROOM PVCCIN_CPU0_VR
J 0
(-3300 2525);
PAINT MONO (-3300 2525);
DISPLAY INVISIBLE (-3300 2525);
FORCEPROP 1 LAST COMMENT_BODY TRUE
J 0
(-3075 2675);
DISPLAY 1.319149 (-3075 2675);
PAINT GREEN (-3075 2675);
DISPLAY INVISIBLE (-3075 2675);
FORCEADD DNS..2
(-1920 1670);
PAINT RED (-1920 1670);
FORCEPROP 2 LAST CDS_LIB mstr_misc
J 0
(-1920 1670);
PAINT ORANGE (-1920 1670);
DISPLAY INVISIBLE (-1920 1670);
FORCEPROP 1 LAST COMMENT_BODY TRUE
R 1
J 0
(-1845 1445);
DISPLAY 0.872340 (-1845 1445);
PAINT GREEN (-1845 1445);
DISPLAY INVISIBLE (-1845 1445);
WIRE 16 -1 (3525 4025)(3525 4000);
WIRE 16 -1 (450 3350)(450 3250);
WIRE 16 -1 (2375 3875)(2375 3800);
WIRE 16 -1 (2625 2975)(2625 2950);
WIRE 16 -1 (2900 2100)(2900 2000);
WIRE 16 -1 (2300 2100)(2300 2000);
WIRE 16 -1 (2600 2100)(2600 2000);
WIRE 16 -1 (850 1050)(850 1000);
WIRE 16 -1 (850 1050)(1400 1050);
WIRE 16 -1 (850 1200)(850 1050);
WIRE 16 -1 (1950 1050)(1400 1050);
WIRE 16 -1 (1400 1200)(1400 1050);
WIRE 16 -1 (1950 1200)(1950 1050);
WIRE 16 -1 (2000 2100)(2000 2000);
WIRE 16 -1 (1550 2100)(1550 2000);
WIRE 16 -1 (1250 2100)(1250 2000);
WIRE 16 -1 (950 2100)(950 2000);
WIRE 16 -1 (650 2100)(650 2000);
WIRE 16 -1 (4025 3650)(4025 3725);
WIRE 16 -1 (4025 3650)(3650 3650);
WIRE 16 -1 (4025 3550)(4025 3650);
WIRE 16 -1 (3650 3650)(3350 3650);
WIRE 16 -1 (3650 3550)(3650 3650);
WIRE 16 -1 (3300 3650)(3350 3650);
WIRE 16 -1 (3350 3550)(3350 3650);
WIRE 16 -1 (3300 2850)(3300 3650);
WIRE 16 -1 (3225 3650)(3300 3650);
WIRE 16 -1 (525 2850)(3300 2850);
WIRE 16 -1 (525 4100)(525 2850);
WIRE 16 -1 (750 4100)(525 4100);
WIRE 16 -1 (4025 3075)(4025 3100);
WIRE 16 -1 (4025 3100)(3650 3100);
WIRE 16 -1 (4025 3350)(4025 3100);
WIRE 16 -1 (3650 3100)(3350 3100);
WIRE 16 -1 (3650 3350)(3650 3100);
WIRE 16 -1 (3350 3350)(3350 3100);
WIRE 16 -1 (1900 3250)(1900 3400);
WIRE 16 -1 (1900 3400)(1900 3450);
WIRE 16 -1 (1750 3400)(1900 3400);
WIRE 16 -1 (1900 3450)(1900 3500);
WIRE 16 -1 (1750 3450)(1900 3450);
WIRE 16 -1 (1900 3500)(1900 3550);
WIRE 16 -1 (1750 3500)(1900 3500);
WIRE 16 -1 (1900 3550)(1750 3550);
WIRE 16 -1 (-2725 3900)(-2725 3950);
WIRE 16 -1 (-2475 3950)(-2725 3950);
WIRE 16 -1 (-2725 4125)(-2725 3950);
WIRE 16 -1 (-2250 3950)(-2475 3950);
WIRE 16 -1 (-2475 4125)(-2475 3950);
WIRE 16 -1 (-2250 3950)(-1950 3950);
WIRE 16 -1 (-2250 4125)(-2250 3950);
WIRE 16 -1 (-1950 3950)(-1650 3950);
WIRE 16 -1 (-1950 4125)(-1950 3950);
WIRE 16 -1 (-1350 3950)(-1650 3950);
WIRE 16 -1 (-1650 4125)(-1650 3950);
WIRE 16 -1 (-1350 3950)(-825 3950);
WIRE 16 -1 (-1350 4125)(-1350 3950);
WIRE 16 -1 (-350 3950)(-825 3950);
WIRE 16 -1 (-825 4125)(-825 3950);
WIRE 16 -1 (-350 4125)(-350 3950);
WIRE 16 -1 (-50 2500)(-50 2450);
WIRE 16 -1 (-50 2450)(75 2450);
WIRE 16 -1 (0 4750)(0 4825);
WIRE 16 -1 (0 4750)(0 4300);
WIRE 16 -1 (0 4750)(-350 4750);
WIRE 16 -1 (-350 4750)(-825 4750);
WIRE 16 -1 (-350 4325)(-350 4750);
WIRE 16 -1 (0 4300)(600 4300);
WIRE 16 -1 (600 4200)(600 4300);
WIRE 16 -1 (600 4300)(750 4300);
WIRE 16 -1 (-1100 4750)(-825 4750);
WIRE 16 -1 (-825 4275)(-825 4750);
WIRE 16 -1 (750 4200)(600 4200);
WIRE 16 -1 (-450 975)(-450 1150);
WIRE 16 -1 (-450 1150)(-625 1150);
WIRE 16 -1 (-500 2475)(-500 2325);
WIRE 16 -1 (-500 2325)(-625 2325);
WIRE 16 -1 (-2725 4700)(-2725 4400);
WIRE 16 -1 (-2475 4400)(-2725 4400);
WIRE 16 -1 (-2725 4325)(-2725 4400);
WIRE 16 -1 (-2250 4400)(-2475 4400);
WIRE 16 -1 (-2475 4325)(-2475 4400);
WIRE 16 -1 (-2250 4400)(-1950 4400);
WIRE 16 -1 (-2250 4325)(-2250 4400);
WIRE 16 -1 (-1950 4400)(-1650 4400);
WIRE 16 -1 (-1950 4325)(-1950 4400);
WIRE 16 -1 (525 4400)(-1650 4400);
WIRE 16 -1 (-1650 4325)(-1650 4400);
WIRE 16 -1 (525 4450)(525 4400);
WIRE 16 -1 (750 4400)(525 4400);
WIRE 16 -1 (750 4450)(525 4450);
WIRE 16 -1 (2900 2600)(2900 2450);
WIRE 16 -1 (2600 2450)(2900 2450);
WIRE 16 -1 (2900 2450)(2900 2250);
WIRE 16 -1 (2300 2450)(2600 2450);
WIRE 16 -1 (2600 2450)(2600 2250);
WIRE 16 -1 (2000 2450)(2300 2450);
WIRE 16 -1 (2300 2450)(2300 2250);
WIRE 16 -1 (2000 2450)(1550 2450);
WIRE 16 -1 (2000 2250)(2000 2450);
WIRE 16 -1 (1250 2450)(1550 2450);
WIRE 16 -1 (1550 2450)(1550 2250);
WIRE 16 -1 (950 2450)(1250 2450);
WIRE 16 -1 (1250 2450)(1250 2250);
WIRE 16 -1 (650 2450)(950 2450);
FORCEPROP 0 LAST VOLTAGE 12
J 0
(925 2500);
DISPLAY 1.021277 (925 2500);
PAINT SKYBLUE (925 2500);
DISPLAY INVISIBLE (925 2500);
WIRE 16 -1 (950 2450)(950 2250);
WIRE 16 -1 (375 2450)(650 2450);
WIRE 16 -1 (650 2250)(650 2450);
WIRE 16 -1 (850 1500)(850 1550);
WIRE 16 -1 (1400 1500)(850 1500);
WIRE 16 -1 (850 1400)(850 1500);
WIRE 16 -1 (1950 1500)(1400 1500);
WIRE 16 -1 (1400 1400)(1400 1500);
WIRE 16 -1 (1950 1400)(1950 1500);
WIRE 68 -1 (550 1900)(1850 1900);
WIRE 68 -1 (1850 1900)(1850 2500);
WIRE 68 -1 (550 1900)(550 2500);
WIRE 68 -1 (550 2500)(1850 2500);
WIRE 3 2175 (500 1850)(3250 1850);
WIRE 3 2175 (3250 2550)(3250 1850);
WIRE 3 2175 (500 2550)(500 1850);
WIRE 3 2175 (500 2550)(3250 2550);
WIRE 68 -1 (1900 2500)(3200 2500);
WIRE 68 -1 (3200 1900)(3200 2500);
WIRE 68 -1 (1900 1900)(1900 2500);
WIRE 68 -1 (1900 1900)(3200 1900);
WIRE 16 -1 (-950 1850)(-1150 1850);
WIRE 16 -1 (-300 1850)(-950 1850);
FORCEPROP 2 LAST SIG_NAME VSENSE_PVCCIO_CPU0_AVSP
J 0
(-925 1863);
DISPLAY 0.617021 (-925 1863);
PAINT ORANGE (-925 1863);
WIRE 16 -1 (-950 2325)(-950 1850);
WIRE 16 -1 (-825 2325)(-950 2325);
WIRE 16 2175 (-1625 2000)(-1625 1150);
WIRE 16 2175 (-1000 2000)(-1625 2000);
WIRE 16 2175 (-1625 1150)(-1000 1150);
WIRE 16 2175 (-1000 1150)(-1000 2000);
WIRE 16 -1 (3525 4300)(3525 4225);
WIRE 16 -1 (1750 4300)(3525 4300);
FORCEPROP 0 LAST SIG_NAME VR_PVCCIO_CPU0_OCSET
J 0
(1840 4310);
DISPLAY 0.617021 (1840 4310);
PAINT ORANGE (1840 4310);
FORCEPROP 2 LASTPROP $XRERR UNIQUE?
J 0
(1600 4310);
DISPLAY 0.638298 (1600 4310);
PAINT MONO (1600 4310);
DISPLAY INVISIBLE (1600 4310);
WIRE 16 -1 (1750 4500)(3000 4500);
FORCEPROP 2 LAST SIG_NAME ISENSE_PVCCIO_CPU0_PH1_IMON
J 2
(2550 4514);
DISPLAY 0.617021 (2550 4514);
PAINT ORANGE (2550 4514);
WIRE 3 2175 (2275 3725)(2750 3725);
WIRE 3 2175 (2750 4200)(2750 3725);
WIRE 3 2175 (2275 4200)(2275 3725);
WIRE 3 2175 (2275 4200)(2750 4200);
WIRE 16 -1 (1750 4150)(1750 4000);
WIRE 16 -1 (2375 4075)(2375 4150);
WIRE 16 -1 (1750 4150)(2375 4150);
FORCEPROP 2 LAST SIG_NAME A_TSENSE_PVCCIO_CPU0
J 2
(2225 4164);
DISPLAY 0.617021 (2225 4164);
PAINT ORANGE (2225 4164);
WIRE 16 -1 (2375 4150)(2825 4150);
WIRE 16 -1 (450 3550)(450 3750);
WIRE 16 -1 (750 3750)(450 3750);
WIRE 16 -1 (450 3750)(450 4825);
WIRE 16 -1 (450 4825)(3100 4825);
FORCEPROP 2 LAST SIG_NAME VR_PVCCIO_CPU0_AIREF1
J 0
(522 4854);
DISPLAY 0.617021 (522 4854);
PAINT ORANGE (522 4854);
WIRE 3 682 (1850 4250)(1950 4250);
WIRE 16 2175 (-925 3975)(-200 3975);
WIRE 16 2175 (-200 4375)(-200 3975);
WIRE 16 2175 (-925 4375)(-925 3975);
WIRE 16 2175 (-925 4375)(-200 4375);
WIRE 16 -1 (-1950 3850)(750 3850);
FORCEPROP 2 LAST SIG_NAME VR_PVCCIO_CPU0_PWM1
J 0
(-1875 3849);
DISPLAY 0.617021 (-1875 3849);
PAINT ORANGE (-1875 3849);
WIRE 3 2175 (-675 3825)(-675 3500);
WIRE 3 2175 (-675 3500)(-325 3500);
WIRE 3 2175 (-675 3825)(-325 3825);
WIRE 3 2175 (-325 3825)(-325 3500);
WIRE 16 -1 (325 3650)(750 3650);
WIRE 16 -1 (325 3650)(325 3750);
WIRE 16 -1 (-375 3750)(325 3750);
FORCEPROP 0 LAST SIG_NAME VR_PVCCIO_CPU0_PH1_BOOT_R
J 0
(-260 3760);
DISPLAY 0.617021 (-260 3760);
PAINT ORANGE (-260 3760);
FORCEPROP 2 LASTPROP $XRERR UNIQUE?
J 0
(-500 3760);
DISPLAY 0.638298 (-500 3760);
PAINT MONO (-500 3760);
DISPLAY INVISIBLE (-500 3760);
WIRE 16 -1 (750 3950)(-150 3950);
FORCEPROP 0 LAST SIG_NAME TP_PVCCIO_CPU0_GL_0
J 0
(-135 3960);
DISPLAY 0.617021 (-135 3960);
PAINT ORANGE (-135 3960);
FORCEPROP 2 LASTPROP $XRERR UNIQUE?
J 0
(-390 3950);
DISPLAY 0.638298 (-390 3950);
PAINT MONO (-390 3950);
DISPLAY INVISIBLE (-390 3950);
WIRE 16 -1 (750 4000)(-150 4000);
FORCEPROP 0 LAST SIG_NAME TP_PVCCIO_CPU0_GL_1
J 0
(-135 4010);
DISPLAY 0.617021 (-135 4010);
PAINT ORANGE (-135 4010);
FORCEPROP 2 LASTPROP $XRERR UNIQUE?
J 0
(-390 4000);
DISPLAY 0.638298 (-390 4000);
PAINT MONO (-390 4000);
DISPLAY INVISIBLE (-390 4000);
WIRE 16 -1 (-1350 4750)(-1300 4750);
WIRE 16 -1 (-1350 4325)(-1350 4500);
WIRE 16 -1 (-1350 4750)(-1350 4500);
WIRE 16 -1 (-1350 4500)(750 4500);
FORCEPROP 0 LAST VOLTAGE 5
J 0
(175 4575);
DISPLAY 1.021277 (175 4575);
PAINT SKYBLUE (175 4575);
DISPLAY INVISIBLE (175 4575);
FORCEPROP 2 LAST SIG_NAME VR_PVCCIO_CPU0_PH1_VCIN
J 0
(-1260 4510);
DISPLAY 0.617021 (-1260 4510);
PAINT ORANGE (-1260 4510);
FORCEPROP 2 LASTPROP $XRERR UNIQUE?
J 0
(-1500 4510);
DISPLAY 0.638298 (-1500 4510);
PAINT MONO (-1500 4510);
DISPLAY INVISIBLE (-1500 4510);
WIRE 16 -1 (-1600 3450)(-1600 3500);
WIRE 16 -1 (325 3600)(750 3600);
WIRE 16 -1 (-1600 3450)(325 3450);
FORCEPROP 0 LAST VOLTAGE 5
J 0
(-1550 3525);
DISPLAY 1.021277 (-1550 3525);
PAINT SKYBLUE (-1550 3525);
DISPLAY INVISIBLE (-1550 3525);
FORCEPROP 2 LAST SIG_NAME VR_PVCCIO_CPU0_PH1_PHASE
J 0
(-1560 3460);
DISPLAY 0.617021 (-1560 3460);
PAINT ORANGE (-1560 3460);
FORCEPROP 2 LASTPROP $XRERR UNIQUE?
J 0
(-1800 3460);
DISPLAY 0.638298 (-1800 3460);
PAINT MONO (-1800 3460);
DISPLAY INVISIBLE (-1800 3460);
WIRE 16 -1 (325 3450)(325 3600);
WIRE 16 -1 (2625 3550)(2625 3650);
WIRE 16 -1 (2625 3650)(2925 3650);
WIRE 16 -1 (1750 3650)(2625 3650);
FORCEPROP 0 LAST VOLTAGE 5
J 0
(2125 3725);
DISPLAY 1.021277 (2125 3725);
PAINT SKYBLUE (2125 3725);
DISPLAY INVISIBLE (2125 3725);
FORCEPROP 2 LAST SIG_NAME VR_PVCCIO_CPU0_PH1_SW
J 0
(1815 3660);
DISPLAY 0.617021 (1815 3660);
PAINT ORANGE (1815 3660);
FORCEPROP 2 LASTPROP $XRERR UNIQUE?
J 0
(1575 3660);
DISPLAY 0.638298 (1575 3660);
PAINT MONO (1575 3660);
DISPLAY INVISIBLE (1575 3660);
WIRE 16 -1 (2625 3275)(2000 3275);
FORCEPROP 2 LAST SIG_NAME VR_PVCCIO_CPU0_PH1_SW_RC
J 0
(2015 3285);
DISPLAY 0.617021 (2015 3285);
PAINT ORANGE (2015 3285);
FORCEPROP 2 LASTPROP $XRERR UNIQUE?
J 0
(1760 3275);
DISPLAY 0.638298 (1760 3275);
PAINT MONO (1760 3275);
DISPLAY INVISIBLE (1760 3275);
WIRE 16 -1 (2625 3275)(2625 3225);
WIRE 16 -1 (2625 3350)(2625 3275);
WIRE 3 2175 (2375 2875)(2875 2875);
WIRE 3 2175 (2875 3700)(2875 2875);
WIRE 3 2175 (2375 3700)(2375 2875);
WIRE 3 2175 (2375 3700)(2875 3700);
WIRE 3 682 (-775 4050)(-875 4050);
WIRE 3 682 (-775 4350)(-775 4050);
WIRE 3 682 (-875 4050)(-875 4350);
WIRE 3 682 (-875 4350)(-775 4350);
WIRE 3 2175 (-1375 4600)(-1025 4600);
WIRE 3 2175 (-1025 4850)(-1025 4600);
WIRE 3 2175 (-1375 4850)(-1375 4600);
WIRE 3 2175 (-1375 4850)(-1025 4850);
WIRE 16 682 (-2425 1950)(-3325 1950);
WIRE 16 682 (-2425 2675)(-2425 1950);
WIRE 16 682 (-3325 1950)(-3325 2675);
WIRE 16 682 (-3325 2675)(-2425 2675);
WIRE 16 -1 (-1925 1400)(-1925 1575);
WIRE 16 -1 (-1925 1400)(-1450 1400);
WIRE 16 -1 (-1925 1400)(-2075 1400);
WIRE 16 -1 (-2075 1600)(-2075 1400);
WIRE 16 -1 (-2475 1600)(-2075 1600);
WIRE 16 -1 (-2475 1400)(-2475 1600);
WIRE 16 -1 (-3175 1400)(-2475 1400);
FORCEPROP 2 LAST SIG_NAME VSENSE_PVCCIO_CPU0_SKT_VRTN
J 0
(-3185 1410);
DISPLAY 0.617021 (-3185 1410);
PAINT ORANGE (-3185 1410);
WIRE 16 -1 (-1925 1775)(-1925 1850);
WIRE 16 -1 (-1925 1850)(-1450 1850);
WIRE 16 -1 (-1925 1850)(-2075 1850);
WIRE 16 -1 (-2075 1650)(-2075 1850);
WIRE 16 -1 (-2475 1650)(-2075 1650);
WIRE 16 -1 (-2475 1850)(-3200 1850);
FORCEPROP 2 LAST SIG_NAME VSENSE_PVCCIO_CPU0_SKT_VSEN
J 0
(-3185 1861);
DISPLAY 0.617021 (-3185 1861);
PAINT ORANGE (-3185 1861);
WIRE 16 -1 (-2475 1850)(-2475 1650);
WIRE 16 2175 (-2425 1425)(-2100 1425);
WIRE 16 2175 (-2425 1850)(-2425 1425);
WIRE 16 2175 (-2100 1425)(-2100 1850);
WIRE 16 2175 (-2100 1850)(-2425 1850);
WIRE 16 -1 (-825 1150)(-950 1150);
WIRE 16 -1 (-950 1150)(-950 1400);
WIRE 16 -1 (-275 1400)(-950 1400);
FORCEPROP 2 LAST SIG_NAME VSENSE_PVCCIO_CPU0_AVSN
J 0
(-937 1413);
DISPLAY 0.617021 (-937 1413);
PAINT ORANGE (-937 1413);
WIRE 16 -1 (-1150 1400)(-950 1400);
WIRE 3 2175 (200 3175)(825 3175);
WIRE 3 2175 (825 3700)(825 3175);
WIRE 3 2175 (200 3700)(200 3175);
WIRE 3 2175 (200 3700)(825 3700);
WIRE 16 -1 (-1600 3700)(-1600 3750);
WIRE 16 -1 (-575 3750)(-1600 3750);
FORCEPROP 0 LAST SIG_NAME VR_PVCCIO_CPU0_PH1_BOOT
J 0
(-1585 3760);
DISPLAY 0.617021 (-1585 3760);
PAINT ORANGE (-1585 3760);
FORCEPROP 2 LASTPROP $XRERR UNIQUE?
J 0
(-1825 3760);
DISPLAY 0.638298 (-1825 3760);
PAINT MONO (-1825 3760);
DISPLAY INVISIBLE (-1825 3760);
WIRE 16 2175 (-1925 3800)(-975 3800);
WIRE 16 2175 (-975 3800)(-975 3375);
WIRE 16 2175 (-1925 3800)(-1925 3375);
WIRE 16 2175 (-1925 3375)(-975 3375);
DOT 1 (1250 2450);
DOT 1 (850 1050);
DOT 1 (850 1500);
DOT 1 (1400 1050);
DOT 1 (1400 1500);
DOT 1 (950 2450);
DOT 1 (1550 2450);
DOT 1 (2000 2450);
DOT 1 (2300 2450);
DOT 1 (2600 2450);
DOT 1 (2900 2450);
DOT 1 (650 2450);
DOT 1 (-350 4750);
DOT 1 (450 3750);
DOT 1 (3350 3650);
DOT 1 (3300 3650);
DOT 1 (2625 3275);
DOT 1 (-1950 3950);
DOT 1 (-1650 3950);
DOT 1 (-1650 4400);
DOT 1 (-1350 3950);
DOT 1 (-1350 4500);
DOT 1 (-1925 1400);
DOT 1 (-2725 3950);
DOT 1 (-2475 3950);
DOT 1 (-2250 3950);
DOT 1 (-2725 4400);
DOT 1 (-2475 4400);
DOT 1 (-2250 4400);
DOT 1 (0 4750);
DOT 1 (1900 3400);
DOT 1 (1900 3450);
DOT 1 (1900 3500);
DOT 1 (2375 4150);
DOT 1 (3650 3650);
DOT 1 (525 4400);
DOT 1 (-1925 1850);
DOT 1 (-950 1400);
DOT 1 (4025 3650);
DOT 1 (-1950 4400);
DOT 1 (-950 1850);
DOT 1 (-825 4750);
DOT 1 (-825 3950);
DOT 1 (4025 3100);
DOT 1 (3650 3100);
DOT 1 (2625 3650);
DOT 1 (600 4300);
FORCENOTE
TP FAB1 CHANGE ONE 100UF CPA TO FOUR 22UF CAPS 0107
(325 1775) 0;
DISPLAY LEFT (325 1775);
DISPLAY 1.021277 (325 1775);
PAINT RED (325 1775);
FORCENOTE
TP FAB1 CHANGE L7C1 PN 0122
(0 2625) 0;
DISPLAY LEFT (0 2625);
DISPLAY 1.021277 (0 2625);
PAINT RED (0 2625);
FORCENOTE
ROUTE AS DIFF PAIR
(-2694 1266) 0;
DISPLAY LEFT (-2694 1266);
DISPLAY 1.021277 (-2694 1266);
PAINT PURPLE (-2694 1266);
FORCENOTE
TP FAB1 CO-LAY WITH TI PARTS 11/16
(2775 3875) 0;
DISPLAY LEFT (2775 3875);
DISPLAY 0.851064 (2775 3875);
PAINT RED (2775 3875);
FORCENOTE
SPOF
(-1304 3251) 0;
DISPLAY LEFT (-1304 3251);
DISPLAY 2.340426 (-1304 3251);
PAINT PURPLE (-1304 3251);
FORCENOTE
PUT TOGETHER
(1900 2500) 0;
DISPLAY LEFT (1900 2500);
DISPLAY 0.808511 (1900 2500);
PAINT PURPLE (1900 2500);
FORCENOTE
PUT TOGETHER
(550 2500) 0;
DISPLAY LEFT (550 2500);
DISPLAY 0.808511 (550 2500);
PAINT PURPLE (550 2500);
FORCENOTE
TOTAL TOL = 1.057VMAX/0.937VMIN
(-3300 2275) 0;
DISPLAY LEFT (-3300 2275);
DISPLAY 0.808511 (-3300 2275);
PAINT PURPLE (-3300 2275);
FORCENOTE
IOUT TDC=14.44A
(-3300 2225) 0;
DISPLAY LEFT (-3300 2225);
DISPLAY 0.808511 (-3300 2225);
PAINT PURPLE (-3300 2225);
FORCENOTE
DC TOL = +/-5MV
(-3300 2325) 0;
DISPLAY LEFT (-3300 2325);
DISPLAY 0.808511 (-3300 2325);
PAINT PURPLE (-3300 2325);
FORCENOTE
IOUT PK= 21.44A
(-3300 2175) 0;
DISPLAY LEFT (-3300 2175);
DISPLAY 0.808511 (-3300 2175);
PAINT PURPLE (-3300 2175);
FORCENOTE
BOOM = PROC_VRD_PVCCIO_CPU0
(-3675 375) 0;
DISPLAY LEFT (-3675 375);
DISPLAY 1.276596 (-3675 375);
PAINT PURPLE (-3675 375);
FORCENOTE
5MIL SPACING
(-2704 1126) 0;
DISPLAY LEFT (-2704 1126);
DISPLAY 1.021277 (-2704 1126);
PAINT PURPLE (-2704 1126);
FORCENOTE
5MIL WIDTH
(-2704 1201) 0;
DISPLAY LEFT (-2704 1201);
DISPLAY 1.021277 (-2704 1201);
PAINT PURPLE (-2704 1201);
FORCENOTE
ROOM = PVCCIO_CPU0
(-3675 450) 0;
DISPLAY LEFT (-3675 450);
DISPLAY 1.276596 (-3675 450);
PAINT PURPLE (-3675 450);
FORCENOTE
VBOOT=1.0V 
(-3300 1975) 0;
DISPLAY LEFT (-3300 1975);
DISPLAY 0.808511 (-3300 1975);
PAINT PURPLE (-3300 1975);
FORCENOTE
SOCKET SIDE
(-3294 1615) 0;
DISPLAY LEFT (-3294 1615);
DISPLAY 1.021277 (-3294 1615);
PAINT PURPLE (-3294 1615);
FORCENOTE
TP FAB1 CO-LAY WITH TI PARTS 11/16
(-800 3350) 0;
DISPLAY LEFT (-800 3350);
DISPLAY 0.851064 (-800 3350);
PAINT RED (-800 3350);
FORCENOTE
VR CONTROLLER SIDE
(-875 1611) 0;
DISPLAY LEFT (-875 1611);
DISPLAY 1.021277 (-875 1611);
PAINT PURPLE (-875 1611);
FORCENOTE
SPOF
(-1325 2017) 0;
DISPLAY LEFT (-1325 2017);
DISPLAY 1.340426 (-1325 2017);
PAINT PURPLE (-1325 2017);
FORCENOTE
SW FREQ=641 KHZ 
(-3300 2025) 0;
DISPLAY LEFT (-3300 2025);
DISPLAY 0.808511 (-3300 2025);
PAINT PURPLE (-3300 2025);
FORCENOTE
IOUT DI/DT =22 A/US
(-3300 2075) 0;
DISPLAY LEFT (-3300 2075);
DISPLAY 0.808511 (-3300 2075);
PAINT PURPLE (-3300 2075);
FORCENOTE
IOUT STEP=14APP
(-3300 2125) 0;
DISPLAY LEFT (-3300 2125);
DISPLAY 0.808511 (-3300 2125);
PAINT PURPLE (-3300 2125);
FORCENOTE
RIPPLE = +/- 10MV
(-3300 2375) 0;
DISPLAY LEFT (-3300 2375);
DISPLAY 0.808511 (-3300 2375);
PAINT PURPLE (-3300 2375);
FORCENOTE
VOUT=1.0V (TYP) SVID
(-3300 2425) 0;
DISPLAY LEFT (-3300 2425);
DISPLAY 0.808511 (-3300 2425);
PAINT PURPLE (-3300 2425);
FORCENOTE
TP FAB1 CHANGE L7C2 PN 0122
(2775 3775) 0;
DISPLAY LEFT (2775 3775);
DISPLAY 1.021277 (2775 3775);
PAINT RED (2775 3775);
FORCENOTE
ROOM= PVCCIO_CPU0
(-1648 3056) 0;
DISPLAY LEFT (-1648 3056);
DISPLAY 1.595745 (-1648 3056);
PAINT PURPLE (-1648 3056);
FORCENOTE
TP FAB1 CHANGE TO 0 OHM 0107
(-1375 4850) 0;
DISPLAY LEFT (-1375 4850);
DISPLAY 0.638298 (-1375 4850);
PAINT RED (-1375 4850);
FORCENOTE
TP FAB1 CHANGE PN 0310
(-825 4400) 0;
DISPLAY LEFT (-825 4400);
DISPLAY 1.021277 (-825 4400);
PAINT RED (-825 4400);
FORCENOTE
TP FAB1 ADD NET NAME 12/04
(1425 2950) 0;
DISPLAY LEFT (1425 2950);
DISPLAY 1.021277 (1425 2950);
PAINT RED (1425 2950);
FORCENOTE
TP FAB1 CHANGE RES TO 1 OHM 0603 0107
(1900 2800) 0;
DISPLAY LEFT (1900 2800);
DISPLAY 1.021277 (1900 2800);
PAINT RED (1900 2800);
FORCENOTE
PLACE ON TOP
(-930 3900) 0;
DISPLAY LEFT (-930 3900);
DISPLAY 1.553191 (-930 3900);
PAINT PURPLE (-930 3900);
FORCENOTE
TDA21460
(1100 4575) 0;
DISPLAY LEFT (1100 4575);
DISPLAY 1.021277 (1100 4575);
PAINT SKYBLUE (1100 4575);
FORCENOTE
TP FAB1 DEL NET 0309
(1975 4225) 0;
DISPLAY LEFT (1975 4225);
DISPLAY 1.021277 (1975 4225);
PAINT RED (1975 4225);
FORCENOTE
TP FAB1 CO-LAY WITH TI PARTS 11/16
(2625 2750) 0;
DISPLAY LEFT (2625 2750);
DISPLAY 0.851064 (2625 2750);
PAINT RED (2625 2750);
QUIT
